(kicad_sch
	(version 20250114)
	(generator "eeschema")
	(generator_version "9.0")
	(paper "A3")
	(title_block
		(title "SO-DIMM DDR5 Tester")
		(date "2025-11-26")
		(rev "1.3.0")
		(company "Antmicro Ltd.")
		(comment 1 "www.antmicro.com")
		(comment 2 "Antmicro Ltd")
	)
	(text "Configuration Modes"
		(exclude_from_sim no)
		(at 302.895 207.01 0)
		(effects
			(font
				(size 2.54 2.54)
				(thickness 0.5994)
				(bold yes)
			)
			(justify left bottom)
		)
	)
	(text "JTAG Connector\n"
		(exclude_from_sim no)
		(at 14.605 207.01 0)
		(effects
			(font
				(size 2.54 2.54)
				(thickness 0.5994)
				(bold yes)
			)
			(justify left bottom)
		)
	)
	(text "000\n001\n010\n100\n101\n110\n111"
		(exclude_from_sim no)
		(at 381 236.855 0)
		(effects
			(font
				(size 1.27 1.27)
			)
			(justify left bottom)
		)
	)
	(text "FPGA BANK 0"
		(exclude_from_sim no)
		(at 15.24 19.685 0)
		(effects
			(font
				(size 2.54 2.54)
				(thickness 0.5994)
				(bold yes)
			)
			(justify left bottom)
		)
	)
	(text "MODE[2:0]"
		(exclude_from_sim no)
		(at 380.873 221.996 0)
		(effects
			(font
				(size 1.27 1.27)
			)
			(justify left bottom)
		)
	)
	(text "Config. mode"
		(exclude_from_sim no)
		(at 362.077 221.996 0)
		(effects
			(font
				(size 1.27 1.27)
			)
			(justify left bottom)
		)
	)
	(text "Compatible with Xilinx Platform Cable"
		(exclude_from_sim no)
		(at 15.24 209.55 0)
		(effects
			(font
				(size 1.27 1.27)
			)
			(justify left bottom)
		)
	)
	(text "Master Serial\nMaster SPI\nMaster BPI\nMaster SelectMAP\nJTAG\nSlave SelectMAP\nSlave Serial"
		(exclude_from_sim no)
		(at 361.95 236.855 0)
		(effects
			(font
				(size 1.27 1.27)
			)
			(justify left bottom)
		)
	)
	(text "For details, see UG470 p. 21"
		(exclude_from_sim no)
		(at 303.53 210.185 0)
		(effects
			(font
				(size 1.27 1.27)
			)
			(justify left bottom)
		)
	)
	(text "STATUS LEDs"
		(exclude_from_sim no)
		(at 114.3 207.01 0)
		(effects
			(font
				(size 2.54 2.54)
				(thickness 0.5994)
				(bold yes)
			)
			(justify left bottom)
		)
	)
	(junction
		(at 171.45 131.445)
		(diameter 0)
		(color 0 0 0 0)
	)
	(junction
		(at 243.205 99.06)
		(diameter 0)
		(color 0 0 0 0)
	)
	(junction
		(at 163.195 111.76)
		(diameter 0)
		(color 0 0 0 0)
	)
	(junction
		(at 313.69 240.03)
		(diameter 0)
		(color 0 0 0 0)
	)
	(junction
		(at 243.205 96.52)
		(diameter 0)
		(color 0 0 0 0)
	)
	(junction
		(at 347.345 220.98)
		(diameter 0)
		(color 0 0 0 0)
	)
	(junction
		(at 163.195 96.52)
		(diameter 0)
		(color 0 0 0 0)
	)
	(junction
		(at 180.34 109.22)
		(diameter 0)
		(color 0 0 0 0)
	)
	(junction
		(at 29.21 229.87)
		(diameter 0)
		(color 0 0 0 0)
	)
	(junction
		(at 313.69 234.95)
		(diameter 0)
		(color 0 0 0 0)
	)
	(junction
		(at 29.21 232.41)
		(diameter 0)
		(color 0 0 0 0)
	)
	(junction
		(at 243.205 91.44)
		(diameter 0)
		(color 0 0 0 0)
	)
	(junction
		(at 29.21 240.03)
		(diameter 0)
		(color 0 0 0 0)
	)
	(junction
		(at 243.205 102.87)
		(diameter 0)
		(color 0 0 0 0)
	)
	(junction
		(at 29.21 237.49)
		(diameter 0)
		(color 0 0 0 0)
	)
	(junction
		(at 29.21 242.57)
		(diameter 0)
		(color 0 0 0 0)
	)
	(junction
		(at 171.45 96.52)
		(diameter 0)
		(color 0 0 0 0)
	)
	(junction
		(at 171.45 114.3)
		(diameter 0)
		(color 0 0 0 0)
	)
	(junction
		(at 313.69 237.49)
		(diameter 0)
		(color 0 0 0 0)
	)
	(junction
		(at 243.205 105.41)
		(diameter 0)
		(color 0 0 0 0)
	)
	(junction
		(at 29.21 234.95)
		(diameter 0)
		(color 0 0 0 0)
	)
	(junction
		(at 171.45 119.38)
		(diameter 0)
		(color 0 0 0 0)
	)
	(no_connect
		(at 42.545 242.57)
	)
	(no_connect
		(at 42.545 240.03)
	)
	(bus_entry
		(at 192.405 96.52)
		(size -2.54 -2.54)
		(stroke
			(width 0)
			(type default)
		)
	)
	(bus_entry
		(at 191.77 88.9)
		(size -2.54 -2.54)
		(stroke
			(width 0)
			(type default)
		)
	)
	(bus_entry
		(at 191.77 83.82)
		(size -2.54 -2.54)
		(stroke
			(width 0)
			(type default)
		)
	)
	(bus_entry
		(at 191.77 91.44)
		(size -2.54 -2.54)
		(stroke
			(width 0)
			(type default)
		)
	)
	(bus_entry
		(at 191.77 86.36)
		(size -2.54 -2.54)
		(stroke
			(width 0)
			(type default)
		)
	)
	(wire
		(pts
			(xy 313.69 234.95) (xy 317.5 234.95)
		)
		(stroke
			(width 0)
			(type default)
		)
	)
	(wire
		(pts
			(xy 32.385 242.57) (xy 29.21 242.57)
		)
		(stroke
			(width 0)
			(type default)
		)
	)
	(wire
		(pts
			(xy 317.5 232.41) (xy 313.69 232.41)
		)
		(stroke
			(width 0)
			(type default)
		)
	)
	(wire
		(pts
			(xy 330.2 237.49) (xy 354.965 237.49)
		)
		(stroke
			(width 0)
			(type default)
		)
	)
	(wire
		(pts
			(xy 29.21 234.95) (xy 29.21 237.49)
		)
		(stroke
			(width 0)
			(type default)
		)
	)
	(wire
		(pts
			(xy 203.2 78.74) (xy 204.47 78.74)
		)
		(stroke
			(width 0)
			(type default)
		)
	)
	(wire
		(pts
			(xy 163.195 111.76) (xy 204.47 111.76)
		)
		(stroke
			(width 0)
			(type default)
		)
	)
	(wire
		(pts
			(xy 42.545 227.33) (xy 47.625 227.33)
		)
		(stroke
			(width 0)
			(type default)
		)
	)
	(wire
		(pts
			(xy 165.1 226.06) (xy 165.1 227.33)
		)
		(stroke
			(width 0)
			(type default)
		)
	)
	(wire
		(pts
			(xy 191.77 88.9) (xy 204.47 88.9)
		)
		(stroke
			(width 0)
			(type default)
		)
	)
	(bus
		(pts
			(xy 189.865 92.71) (xy 189.865 93.98)
		)
		(stroke
			(width 0)
			(type default)
		)
	)
	(wire
		(pts
			(xy 347.345 220.98) (xy 347.345 223.52)
		)
		(stroke
			(width 0)
			(type default)
		)
	)
	(wire
		(pts
			(xy 243.205 88.9) (xy 243.205 91.44)
		)
		(stroke
			(width 0)
			(type default)
		)
	)
	(wire
		(pts
			(xy 191.77 86.36) (xy 204.47 86.36)
		)
		(stroke
			(width 0)
			(type default)
		)
	)
	(wire
		(pts
			(xy 347.345 228.6) (xy 347.345 234.95)
		)
		(stroke
			(width 0)
			(type default)
		)
	)
	(wire
		(pts
			(xy 173.99 131.445) (xy 173.99 130.81)
		)
		(stroke
			(width 0)
			(type default)
		)
	)
	(polyline
		(pts
			(xy 361.188 222.504) (xy 391.033 222.504)
		)
		(stroke
			(width 0.1016)
			(type solid)
		)
	)
	(polyline
		(pts
			(xy 380.365 219.71) (xy 380.365 236.855)
		)
		(stroke
			(width 0.1016)
			(type solid)
		)
	)
	(wire
		(pts
			(xy 171.45 114.3) (xy 171.45 119.38)
		)
		(stroke
			(width 0)
			(type default)
		)
	)
	(wire
		(pts
			(xy 207.01 255.27) (xy 207.01 256.54)
		)
		(stroke
			(width 0)
			(type default)
		)
	)
	(wire
		(pts
			(xy 32.385 234.95) (xy 29.21 234.95)
		)
		(stroke
			(width 0)
			(type default)
		)
	)
	(wire
		(pts
			(xy 192.405 96.52) (xy 204.47 96.52)
		)
		(stroke
			(width 0)
			(type default)
		)
	)
	(wire
		(pts
			(xy 313.69 240.03) (xy 313.69 243.205)
		)
		(stroke
			(width 0)
			(type default)
		)
	)
	(wire
		(pts
			(xy 354.965 220.98) (xy 347.345 220.98)
		)
		(stroke
			(width 0)
			(type default)
		)
	)
	(wire
		(pts
			(xy 32.385 240.03) (xy 29.21 240.03)
		)
		(stroke
			(width 0)
			(type default)
		)
	)
	(wire
		(pts
			(xy 207.01 234.95) (xy 207.01 236.22)
		)
		(stroke
			(width 0)
			(type default)
		)
	)
	(wire
		(pts
			(xy 250.19 255.27) (xy 250.19 256.54)
		)
		(stroke
			(width 0)
			(type default)
		)
	)
	(wire
		(pts
			(xy 42.545 237.49) (xy 53.975 237.49)
		)
		(stroke
			(width 0)
			(type default)
		)
	)
	(wire
		(pts
			(xy 163.195 94.615) (xy 163.195 96.52)
		)
		(stroke
			(width 0)
			(type default)
		)
	)
	(wire
		(pts
			(xy 313.69 240.03) (xy 317.5 240.03)
		)
		(stroke
			(width 0)
			(type default)
		)
	)
	(wire
		(pts
			(xy 165.1 234.95) (xy 165.1 236.22)
		)
		(stroke
			(width 0)
			(type default)
		)
	)
	(wire
		(pts
			(xy 29.21 229.87) (xy 29.21 232.41)
		)
		(stroke
			(width 0)
			(type default)
		)
	)
	(wire
		(pts
			(xy 204.47 101.6) (xy 193.675 101.6)
		)
		(stroke
			(width 0)
			(type default)
		)
	)
	(wire
		(pts
			(xy 240.03 83.82) (xy 248.285 83.82)
		)
		(stroke
			(width 0)
			(type default)
		)
	)
	(wire
		(pts
			(xy 171.45 96.52) (xy 171.45 99.695)
		)
		(stroke
			(width 0)
			(type default)
		)
	)
	(wire
		(pts
			(xy 354.965 223.52) (xy 354.965 220.98)
		)
		(stroke
			(width 0)
			(type default)
		)
	)
	(wire
		(pts
			(xy 91.44 240.03) (xy 91.44 244.475)
		)
		(stroke
			(width 0)
			(type default)
		)
	)
	(wire
		(pts
			(xy 248.285 76.2) (xy 248.285 76.835)
		)
		(stroke
			(width 0)
			(type default)
		)
	)
	(wire
		(pts
			(xy 171.45 131.445) (xy 173.99 131.445)
		)
		(stroke
			(width 0)
			(type default)
		)
	)
	(wire
		(pts
			(xy 207.01 242.57) (xy 207.01 241.3)
		)
		(stroke
			(width 0)
			(type default)
		)
	)
	(wire
		(pts
			(xy 240.03 102.87) (xy 243.205 102.87)
		)
		(stroke
			(width 0)
			(type default)
		)
	)
	(wire
		(pts
			(xy 180.34 109.22) (xy 204.47 109.22)
		)
		(stroke
			(width 0)
			(type default)
		)
	)
	(wire
		(pts
			(xy 29.21 242.57) (xy 29.21 247.015)
		)
		(stroke
			(width 0)
			(type default)
		)
	)
	(wire
		(pts
			(xy 171.45 130.81) (xy 171.45 131.445)
		)
		(stroke
			(width 0)
			(type default)
		)
	)
	(wire
		(pts
			(xy 243.205 99.06) (xy 240.03 99.06)
		)
		(stroke
			(width 0)
			(type default)
		)
	)
	(wire
		(pts
			(xy 339.09 220.98) (xy 339.09 223.52)
		)
		(stroke
			(width 0)
			(type default)
		)
	)
	(bus
		(pts
			(xy 187.96 92.075) (xy 189.23 92.075)
		)
		(stroke
			(width 0)
			(type default)
		)
	)
	(wire
		(pts
			(xy 204.47 104.14) (xy 193.675 104.14)
		)
		(stroke
			(width 0)
			(type default)
		)
	)
	(wire
		(pts
			(xy 163.195 99.695) (xy 163.195 96.52)
		)
		(stroke
			(width 0)
			(type default)
		)
	)
	(bus
		(pts
			(xy 188.595 79.375) (xy 189.23 80.01)
		)
		(stroke
			(width 0)
			(type default)
		)
	)
	(wire
		(pts
			(xy 313.69 234.95) (xy 313.69 237.49)
		)
		(stroke
			(width 0)
			(type default)
		)
	)
	(wire
		(pts
			(xy 32.385 229.87) (xy 29.21 229.87)
		)
		(stroke
			(width 0)
			(type default)
		)
	)
	(wire
		(pts
			(xy 88.9 234.95) (xy 97.79 234.95)
		)
		(stroke
			(width 0)
			(type default)
		)
	)
	(wire
		(pts
			(xy 236.22 251.46) (xy 242.57 251.46)
		)
		(stroke
			(width 0)
			(type default)
		)
	)
	(wire
		(pts
			(xy 330.2 234.95) (xy 347.345 234.95)
		)
		(stroke
			(width 0)
			(type default)
		)
	)
	(wire
		(pts
			(xy 191.77 251.46) (xy 199.39 251.46)
		)
		(stroke
			(width 0)
			(type default)
		)
	)
	(wire
		(pts
			(xy 243.205 88.9) (xy 240.03 88.9)
		)
		(stroke
			(width 0)
			(type default)
		)
	)
	(wire
		(pts
			(xy 165.1 242.57) (xy 165.1 241.3)
		)
		(stroke
			(width 0)
			(type default)
		)
	)
	(polyline
		(pts
			(xy 12.065 200.025) (xy 408.305 200.025)
		)
		(stroke
			(width 0)
			(type default)
		)
	)
	(wire
		(pts
			(xy 180.34 99.695) (xy 180.34 96.52)
		)
		(stroke
			(width 0)
			(type default)
		)
	)
	(polyline
		(pts
			(xy 299.72 200.66) (xy 299.72 252.095)
		)
		(stroke
			(width 0)
			(type default)
		)
	)
	(wire
		(pts
			(xy 88.9 237.49) (xy 97.79 237.49)
		)
		(stroke
			(width 0)
			(type default)
		)
	)
	(wire
		(pts
			(xy 29.21 227.33) (xy 29.21 229.87)
		)
		(stroke
			(width 0)
			(type default)
		)
	)
	(wire
		(pts
			(xy 88.9 232.41) (xy 97.79 232.41)
		)
		(stroke
			(width 0)
			(type default)
		)
	)
	(wire
		(pts
			(xy 330.2 232.41) (xy 339.09 232.41)
		)
		(stroke
			(width 0)
			(type default)
		)
	)
	(wire
		(pts
			(xy 47.625 227.33) (xy 47.625 222.885)
		)
		(stroke
			(width 0)
			(type default)
		)
	)
	(wire
		(pts
			(xy 204.47 99.06) (xy 193.675 99.06)
		)
		(stroke
			(width 0)
			(type default)
		)
	)
	(wire
		(pts
			(xy 250.19 242.57) (xy 250.19 241.3)
		)
		(stroke
			(width 0)
			(type default)
		)
	)
	(wire
		(pts
			(xy 207.01 226.06) (xy 207.01 227.33)
		)
		(stroke
			(width 0)
			(type default)
		)
	)
	(wire
		(pts
			(xy 354.965 228.6) (xy 354.965 237.49)
		)
		(stroke
			(width 0)
			(type default)
		)
	)
	(wire
		(pts
			(xy 243.205 91.44) (xy 243.205 96.52)
		)
		(stroke
			(width 0)
			(type default)
		)
	)
	(wire
		(pts
			(xy 347.345 220.98) (xy 339.09 220.98)
		)
		(stroke
			(width 0)
			(type default)
		)
	)
	(wire
		(pts
			(xy 32.385 227.33) (xy 29.21 227.33)
		)
		(stroke
			(width 0)
			(type default)
		)
	)
	(wire
		(pts
			(xy 313.69 232.41) (xy 313.69 234.95)
		)
		(stroke
			(width 0)
			(type default)
		)
	)
	(wire
		(pts
			(xy 243.205 99.06) (xy 243.205 102.87)
		)
		(stroke
			(width 0)
			(type default)
		)
	)
	(wire
		(pts
			(xy 180.34 96.52) (xy 171.45 96.52)
		)
		(stroke
			(width 0)
			(type default)
		)
	)
	(polyline
		(pts
			(xy 112.395 285.115) (xy 112.395 200.025)
		)
		(stroke
			(width 0)
			(type default)
		)
	)
	(wire
		(pts
			(xy 173.99 119.38) (xy 171.45 119.38)
		)
		(stroke
			(width 0)
			(type default)
		)
	)
	(wire
		(pts
			(xy 173.99 120.65) (xy 173.99 119.38)
		)
		(stroke
			(width 0)
			(type default)
		)
	)
	(bus
		(pts
			(xy 189.23 86.36) (xy 189.23 88.9)
		)
		(stroke
			(width 0)
			(type default)
		)
	)
	(bus
		(pts
			(xy 189.23 92.075) (xy 189.865 92.71)
		)
		(stroke
			(width 0)
			(type default)
		)
	)
	(wire
		(pts
			(xy 32.385 232.41) (xy 29.21 232.41)
		)
		(stroke
			(width 0)
			(type default)
		)
	)
	(wire
		(pts
			(xy 88.9 229.87) (xy 97.79 229.87)
		)
		(stroke
			(width 0)
			(type default)
		)
	)
	(wire
		(pts
			(xy 29.21 240.03) (xy 29.21 242.57)
		)
		(stroke
			(width 0)
			(type default)
		)
	)
	(wire
		(pts
			(xy 171.45 131.445) (xy 171.45 133.35)
		)
		(stroke
			(width 0)
			(type default)
		)
	)
	(bus
		(pts
			(xy 189.23 80.01) (xy 189.23 81.28)
		)
		(stroke
			(width 0)
			(type default)
		)
	)
	(wire
		(pts
			(xy 165.1 255.27) (xy 165.1 256.54)
		)
		(stroke
			(width 0)
			(type default)
		)
	)
	(wire
		(pts
			(xy 88.9 240.03) (xy 91.44 240.03)
		)
		(stroke
			(width 0)
			(type default)
		)
	)
	(wire
		(pts
			(xy 29.21 237.49) (xy 29.21 240.03)
		)
		(stroke
			(width 0)
			(type default)
		)
	)
	(wire
		(pts
			(xy 203.2 76.835) (xy 203.2 78.74)
		)
		(stroke
			(width 0)
			(type default)
		)
	)
	(wire
		(pts
			(xy 163.195 96.52) (xy 171.45 96.52)
		)
		(stroke
			(width 0)
			(type default)
		)
	)
	(bus
		(pts
			(xy 189.23 81.28) (xy 189.23 83.82)
		)
		(stroke
			(width 0)
			(type default)
		)
	)
	(wire
		(pts
			(xy 180.34 104.775) (xy 180.34 109.22)
		)
		(stroke
			(width 0)
			(type default)
		)
	)
	(wire
		(pts
			(xy 163.195 104.775) (xy 163.195 111.76)
		)
		(stroke
			(width 0)
			(type default)
		)
	)
	(wire
		(pts
			(xy 153.035 109.22) (xy 180.34 109.22)
		)
		(stroke
			(width 0)
			(type default)
		)
	)
	(wire
		(pts
			(xy 171.45 104.775) (xy 171.45 114.3)
		)
		(stroke
			(width 0)
			(type default)
		)
	)
	(wire
		(pts
			(xy 42.545 232.41) (xy 53.975 232.41)
		)
		(stroke
			(width 0)
			(type default)
		)
	)
	(bus
		(pts
			(xy 189.23 83.82) (xy 189.23 86.36)
		)
		(stroke
			(width 0)
			(type default)
		)
	)
	(wire
		(pts
			(xy 171.45 119.38) (xy 171.45 120.65)
		)
		(stroke
			(width 0)
			(type default)
		)
	)
	(wire
		(pts
			(xy 250.19 226.06) (xy 250.19 227.33)
		)
		(stroke
			(width 0)
			(type default)
		)
	)
	(wire
		(pts
			(xy 347.345 220.98) (xy 347.345 219.71)
		)
		(stroke
			(width 0)
			(type default)
		)
	)
	(wire
		(pts
			(xy 243.205 91.44) (xy 240.03 91.44)
		)
		(stroke
			(width 0)
			(type default)
		)
	)
	(wire
		(pts
			(xy 250.19 234.95) (xy 250.19 236.22)
		)
		(stroke
			(width 0)
			(type default)
		)
	)
	(wire
		(pts
			(xy 243.205 96.52) (xy 240.03 96.52)
		)
		(stroke
			(width 0)
			(type default)
		)
	)
	(wire
		(pts
			(xy 32.385 237.49) (xy 29.21 237.49)
		)
		(stroke
			(width 0)
			(type default)
		)
	)
	(wire
		(pts
			(xy 243.205 96.52) (xy 243.205 99.06)
		)
		(stroke
			(width 0)
			(type default)
		)
	)
	(wire
		(pts
			(xy 243.205 105.41) (xy 240.03 105.41)
		)
		(stroke
			(width 0)
			(type default)
		)
	)
	(wire
		(pts
			(xy 313.69 237.49) (xy 313.69 240.03)
		)
		(stroke
			(width 0)
			(type default)
		)
	)
	(wire
		(pts
			(xy 29.21 232.41) (xy 29.21 234.95)
		)
		(stroke
			(width 0)
			(type default)
		)
	)
	(wire
		(pts
			(xy 313.69 237.49) (xy 317.5 237.49)
		)
		(stroke
			(width 0)
			(type default)
		)
	)
	(wire
		(pts
			(xy 243.205 105.41) (xy 243.205 118.745)
		)
		(stroke
			(width 0)
			(type default)
		)
	)
	(wire
		(pts
			(xy 191.77 83.82) (xy 204.47 83.82)
		)
		(stroke
			(width 0)
			(type default)
		)
	)
	(wire
		(pts
			(xy 42.545 234.95) (xy 53.975 234.95)
		)
		(stroke
			(width 0)
			(type default)
		)
	)
	(wire
		(pts
			(xy 156.21 251.46) (xy 157.48 251.46)
		)
		(stroke
			(width 0)
			(type default)
		)
	)
	(wire
		(pts
			(xy 171.45 114.3) (xy 204.47 114.3)
		)
		(stroke
			(width 0)
			(type default)
		)
	)
	(wire
		(pts
			(xy 171.45 114.3) (xy 153.035 114.3)
		)
		(stroke
			(width 0)
			(type default)
		)
	)
	(wire
		(pts
			(xy 248.285 83.82) (xy 248.285 81.915)
		)
		(stroke
			(width 0)
			(type default)
		)
	)
	(bus
		(pts
			(xy 186.69 79.375) (xy 188.595 79.375)
		)
		(stroke
			(width 0)
			(type default)
		)
	)
	(wire
		(pts
			(xy 42.545 229.87) (xy 53.975 229.87)
		)
		(stroke
			(width 0)
			(type default)
		)
	)
	(wire
		(pts
			(xy 339.09 228.6) (xy 339.09 232.41)
		)
		(stroke
			(width 0)
			(type default)
		)
	)
	(wire
		(pts
			(xy 191.77 91.44) (xy 204.47 91.44)
		)
		(stroke
			(width 0)
			(type default)
		)
	)
	(wire
		(pts
			(xy 243.205 102.87) (xy 243.205 105.41)
		)
		(stroke
			(width 0)
			(type default)
		)
	)
	(wire
		(pts
			(xy 153.035 111.76) (xy 163.195 111.76)
		)
		(stroke
			(width 0)
			(type default)
		)
	)
	(label "JTAG.TDI"
		(at 53.975 237.49 180)
		(effects
			(font
				(size 1.27 1.27)
			)
			(justify right bottom)
		)
	)
	(label "MODE0"
		(at 330.835 232.41 0)
		(effects
			(font
				(size 1.27 1.27)
			)
			(justify left bottom)
		)
	)
	(label "MODE0"
		(at 193.675 99.06 0)
		(effects
			(font
				(size 1.27 1.27)
			)
			(justify left bottom)
		)
	)
	(label "DONE"
		(at 153.035 109.22 0)
		(effects
			(font
				(size 1.27 1.27)
			)
			(justify left bottom)
		)
	)
	(label "PROGRAM_B"
		(at 153.035 114.3 0)
		(effects
			(font
				(size 1.27 1.27)
			)
			(justify left bottom)
		)
	)
	(label "JTAG.TDO"
		(at 97.79 234.95 180)
		(effects
			(font
				(size 1.27 1.27)
			)
			(justify right bottom)
		)
	)
	(label "INIT_B"
		(at 191.77 251.46 0)
		(effects
			(font
				(size 1.27 1.27)
			)
			(justify left bottom)
		)
	)
	(label "MODE1"
		(at 330.835 234.95 0)
		(effects
			(font
				(size 1.27 1.27)
			)
			(justify left bottom)
		)
	)
	(label "JTAG.TCK"
		(at 53.975 232.41 180)
		(effects
			(font
				(size 1.27 1.27)
			)
			(justify right bottom)
		)
	)
	(label "JTAG.TCK"
		(at 203.835 91.44 180)
		(effects
			(font
				(size 1.27 1.27)
			)
			(justify right bottom)
		)
	)
	(label "MODE2"
		(at 330.835 237.49 0)
		(effects
			(font
				(size 1.27 1.27)
			)
			(justify left bottom)
		)
	)
	(label "MODE2"
		(at 193.675 104.14 0)
		(effects
			(font
				(size 1.27 1.27)
			)
			(justify left bottom)
		)
	)
	(label "JTAG.TCK"
		(at 97.79 232.41 180)
		(effects
			(font
				(size 1.27 1.27)
			)
			(justify right bottom)
		)
	)
	(label "JTAG.TDO"
		(at 203.835 86.36 180)
		(effects
			(font
				(size 1.27 1.27)
			)
			(justify right bottom)
		)
	)
	(label "JTAG.TMS"
		(at 53.975 229.87 180)
		(effects
			(font
				(size 1.27 1.27)
			)
			(justify right bottom)
		)
	)
	(label "CFGBVS"
		(at 240.03 83.82 0)
		(effects
			(font
				(size 1.27 1.27)
			)
			(justify left bottom)
		)
	)
	(label "JTAG.TMS"
		(at 203.835 88.9 180)
		(effects
			(font
				(size 1.27 1.27)
			)
			(justify right bottom)
		)
	)
	(label "MODE1"
		(at 193.675 101.6 0)
		(effects
			(font
				(size 1.27 1.27)
			)
			(justify left bottom)
		)
	)
	(label "INIT_B"
		(at 153.035 111.76 0)
		(effects
			(font
				(size 1.27 1.27)
			)
			(justify left bottom)
		)
	)
	(label "FLASH.SCK"
		(at 193.675 96.52 0)
		(effects
			(font
				(size 1.27 1.27)
			)
			(justify left bottom)
		)
	)
	(label "JTAG.TDI"
		(at 203.835 83.82 180)
		(effects
			(font
				(size 1.27 1.27)
			)
			(justify right bottom)
		)
	)
	(label "DONE"
		(at 236.22 251.46 0)
		(effects
			(font
				(size 1.27 1.27)
			)
			(justify left bottom)
		)
	)
	(label "JTAG.TDO"
		(at 53.975 234.95 180)
		(effects
			(font
				(size 1.27 1.27)
			)
			(justify right bottom)
		)
	)
	(label "JTAG.TDI"
		(at 97.79 237.49 180)
		(effects
			(font
				(size 1.27 1.27)
			)
			(justify right bottom)
		)
	)
	(label "JTAG.TMS"
		(at 97.79 229.87 180)
		(effects
			(font
				(size 1.27 1.27)
			)
			(justify right bottom)
		)
	)
	(global_label "POWER"
		(shape input)
		(at 156.21 251.46 180)
		(fields_autoplaced yes)
		(effects
			(font
				(size 1.27 1.27)
			)
			(justify right)
		)
		(property "Intersheetrefs" "${INTERSHEET_REFS}"
			(at 147.4148 251.5394 0)
			(effects
				(font
					(size 1.27 1.27)
				)
				(justify right)
			)
		)
	)
	(hierarchical_label "JTAG{JTAG}"
		(shape bidirectional)
		(at 186.69 79.375 180)
		(effects
			(font
				(size 1.27 1.27)
			)
			(justify right)
		)
	)
	(hierarchical_label "FLASH{QSPI}"
		(shape bidirectional)
		(at 187.96 92.075 180)
		(effects
			(font
				(size 1.27 1.27)
			)
			(justify right)
		)
	)
	(symbol
		(lib_id "antmicropower:GND")
		(at 29.21 247.015 0)
		(unit 1)
		(exclude_from_sim no)
		(in_bom yes)
		(on_board yes)
		(dnp no)
		(property "Reference" "#PWR0182"
			(at 29.21 253.365 0)
			(effects
				(font
					(size 1.27 1.27)
				)
				(hide yes)
			)
		)
		(property "Value" "GND"
			(at 27.178 251.333 0)
			(effects
				(font
					(size 1.27 1.27)
					(thickness 0.15)
				)
				(justify left)
			)
		)
		(property "Footprint" ""
			(at 38.1 254.635 0)
			(effects
				(font
					(size 1.27 1.27)
					(thickness 0.15)
				)
				(justify left bottom)
				(hide yes)
			)
		)
		(property "Datasheet" ""
			(at 38.1 259.715 0)
			(effects
				(font
					(size 1.27 1.27)
					(thickness 0.15)
				)
				(justify left bottom)
				(hide yes)
			)
		)
		(property "Description" ""
			(at 38.1 262.255 0)
			(effects
				(font
					(size 1.27 1.27)
				)
				(justify left bottom)
				(hide yes)
			)
		)
		(property "Author" "Antmicro"
			(at 38.1 254.635 0)
			(effects
				(font
					(size 1.27 1.27)
					(thickness 0.15)
				)
				(justify left bottom)
				(hide yes)
			)
		)
		(property "License" "Apache-2.0"
			(at 38.1 257.175 0)
			(effects
				(font
					(size 1.27 1.27)
					(thickness 0.15)
				)
				(justify left bottom)
				(hide yes)
			)
		)
		(pin "1"
		)
		(instances
			(project "sodimm-ddr5-tester"
				(path ""
					(reference "#PWR0182")
					(unit 1)
				)
			)
		)
	)
	(symbol
		(lib_id "antmicropower:GND")
		(at 91.44 244.475 0)
		(unit 1)
		(exclude_from_sim no)
		(in_bom yes)
		(on_board yes)
		(dnp no)
		(property "Reference" "#PWR0183"
			(at 91.44 250.825 0)
			(effects
				(font
					(size 1.27 1.27)
				)
				(hide yes)
			)
		)
		(property "Value" "GND"
			(at 89.408 248.793 0)
			(effects
				(font
					(size 1.27 1.27)
					(thickness 0.15)
				)
				(justify left)
			)
		)
		(property "Footprint" ""
			(at 100.33 252.095 0)
			(effects
				(font
					(size 1.27 1.27)
					(thickness 0.15)
				)
				(justify left bottom)
				(hide yes)
			)
		)
		(property "Datasheet" ""
			(at 100.33 257.175 0)
			(effects
				(font
					(size 1.27 1.27)
					(thickness 0.15)
				)
				(justify left bottom)
				(hide yes)
			)
		)
		(property "Description" ""
			(at 100.33 259.715 0)
			(effects
				(font
					(size 1.27 1.27)
				)
				(justify left bottom)
				(hide yes)
			)
		)
		(property "Author" "Antmicro"
			(at 100.33 252.095 0)
			(effects
				(font
					(size 1.27 1.27)
					(thickness 0.15)
				)
				(justify left bottom)
				(hide yes)
			)
		)
		(property "License" "Apache-2.0"
			(at 100.33 254.635 0)
			(effects
				(font
					(size 1.27 1.27)
					(thickness 0.15)
				)
				(justify left bottom)
				(hide yes)
			)
		)
		(pin "1"
		)
		(instances
			(project "sodimm-ddr5-tester"
				(path ""
					(reference "#PWR0183")
					(unit 1)
				)
			)
		)
	)
	(symbol
		(lib_id "antmicroResistors0402:R_4k7_0402")
		(at 171.45 99.695 270)
		(unit 1)
		(exclude_from_sim no)
		(in_bom yes)
		(on_board yes)
		(dnp no)
		(property "Reference" "R18"
			(at 172.085 99.06 90)
			(effects
				(font
					(size 1.27 1.27)
				)
				(justify left)
			)
		)
		(property "Value" "R_4k7_0402"
			(at 158.75 120.015 0)
			(effects
				(font
					(size 1.27 1.27)
					(thickness 0.15)
				)
				(justify left bottom)
				(hide yes)
			)
		)
		(property "Footprint" "antmicro-footprints:R_0402_1005Metric"
			(at 156.21 120.015 0)
			(effects
				(font
					(size 1.27 1.27)
					(thickness 0.15)
				)
				(justify left bottom)
				(hide yes)
			)
		)
		(property "Datasheet" "https://www.bourns.com/docs/product-datasheets/cr.pdf"
			(at 153.67 120.015 0)
			(effects
				(font
					(size 1.27 1.27)
					(thickness 0.15)
				)
				(justify left bottom)
				(hide yes)
			)
		)
		(property "Description" ""
			(at 171.45 99.695 0)
			(effects
				(font
					(size 1.27 1.27)
				)
			)
		)
		(property "Manufacturer" "Bourns"
			(at 148.59 120.015 0)
			(effects
				(font
					(size 1.27 1.27)
					(thickness 0.15)
				)
				(justify left bottom)
				(hide yes)
			)
		)
		(property "MPN" "CR0402-FX-4701GLF"
			(at 151.13 120.015 0)
			(effects
				(font
					(size 1.27 1.27)
					(thickness 0.15)
				)
				(justify left bottom)
				(hide yes)
			)
		)
		(property "Val" "4k7"
			(at 173.355 104.1399 90)
			(effects
				(font
					(size 1.27 1.27)
					(thickness 0.15)
				)
				(justify left)
			)
		)
		(property "License" "Apache-2.0"
			(at 146.05 120.015 0)
			(effects
				(font
					(size 1.27 1.27)
					(thickness 0.15)
				)
				(justify left bottom)
				(hide yes)
			)
		)
		(property "Author" "Antmicro"
			(at 143.51 120.015 0)
			(effects
				(font
					(size 1.27 1.27)
					(thickness 0.15)
				)
				(justify left bottom)
				(hide yes)
			)
		)
		(property "Tolerance" "1%"
			(at 161.29 120.015 0)
			(effects
				(font
					(size 1.27 1.27)
				)
				(justify left bottom)
				(hide yes)
			)
		)
		(pin "1"
		)
		(pin "2"
		)
		(instances
			(project "sodimm-ddr5-tester"
				(path ""
					(reference "R18")
					(unit 1)
				)
			)
		)
	)
	(symbol
		(lib_id "antmicroResistors0402:R_330R_0402")
		(at 180.34 99.695 270)
		(unit 1)
		(exclude_from_sim no)
		(in_bom yes)
		(on_board yes)
		(dnp no)
		(property "Reference" "R19"
			(at 180.975 99.06 90)
			(effects
				(font
					(size 1.27 1.27)
				)
				(justify left)
			)
		)
		(property "Value" "R_330R_0402"
			(at 167.64 120.015 0)
			(effects
				(font
					(size 1.27 1.27)
					(thickness 0.15)
				)
				(justify left bottom)
				(hide yes)
			)
		)
		(property "Footprint" "antmicro-footprints:R_0402_1005Metric"
			(at 165.1 120.015 0)
			(effects
				(font
					(size 1.27 1.27)
					(thickness 0.15)
				)
				(justify left bottom)
				(hide yes)
			)
		)
		(property "Datasheet" "https://www.bourns.com/docs/product-datasheets/cr.pdf"
			(at 162.56 120.015 0)
			(effects
				(font
					(size 1.27 1.27)
					(thickness 0.15)
				)
				(justify left bottom)
				(hide yes)
			)
		)
		(property "Description" ""
			(at 180.34 99.695 0)
			(effects
				(font
					(size 1.27 1.27)
				)
			)
		)
		(property "Manufacturer" "Bourns"
			(at 157.48 120.015 0)
			(effects
				(font
					(size 1.27 1.27)
					(thickness 0.15)
				)
				(justify left bottom)
				(hide yes)
			)
		)
		(property "MPN" "CR0402-FX-3300GLF"
			(at 160.02 120.015 0)
			(effects
				(font
					(size 1.27 1.27)
					(thickness 0.15)
				)
				(justify left bottom)
				(hide yes)
			)
		)
		(property "Val" "330R"
			(at 182.245 104.1399 90)
			(effects
				(font
					(size 1.27 1.27)
					(thickness 0.15)
				)
				(justify left)
			)
		)
		(property "License" "Apache-2.0"
			(at 154.94 120.015 0)
			(effects
				(font
					(size 1.27 1.27)
					(thickness 0.15)
				)
				(justify left bottom)
				(hide yes)
			)
		)
		(property "Author" "Antmicro"
			(at 152.4 120.015 0)
			(effects
				(font
					(size 1.27 1.27)
					(thickness 0.15)
				)
				(justify left bottom)
				(hide yes)
			)
		)
		(property "Tolerance" "1%"
			(at 170.18 120.015 0)
			(effects
				(font
					(size 1.27 1.27)
				)
				(justify left bottom)
				(hide yes)
			)
		)
		(pin "1"
		)
		(pin "2"
		)
		(instances
			(project "sodimm-ddr5-tester"
				(path ""
					(reference "R19")
					(unit 1)
				)
			)
		)
	)
	(symbol
		(lib_id "antmicropower:GND")
		(at 250.19 256.54 0)
		(unit 1)
		(exclude_from_sim no)
		(in_bom yes)
		(on_board yes)
		(dnp no)
		(property "Reference" "#PWR0186"
			(at 250.19 262.89 0)
			(effects
				(font
					(size 1.27 1.27)
				)
				(hide yes)
			)
		)
		(property "Value" "GND"
			(at 248.158 260.858 0)
			(effects
				(font
					(size 1.27 1.27)
					(thickness 0.15)
				)
				(justify left)
			)
		)
		(property "Footprint" ""
			(at 259.08 264.16 0)
			(effects
				(font
					(size 1.27 1.27)
					(thickness 0.15)
				)
				(justify left bottom)
				(hide yes)
			)
		)
		(property "Datasheet" ""
			(at 259.08 269.24 0)
			(effects
				(font
					(size 1.27 1.27)
					(thickness 0.15)
				)
				(justify left bottom)
				(hide yes)
			)
		)
		(property "Description" ""
			(at 259.08 271.78 0)
			(effects
				(font
					(size 1.27 1.27)
				)
				(justify left bottom)
				(hide yes)
			)
		)
		(property "Author" "Antmicro"
			(at 259.08 264.16 0)
			(effects
				(font
					(size 1.27 1.27)
					(thickness 0.15)
				)
				(justify left bottom)
				(hide yes)
			)
		)
		(property "License" "Apache-2.0"
			(at 259.08 266.7 0)
			(effects
				(font
					(size 1.27 1.27)
					(thickness 0.15)
				)
				(justify left bottom)
				(hide yes)
			)
		)
		(pin "1"
		)
		(instances
			(project "sodimm-ddr5-tester"
				(path ""
					(reference "#PWR0186")
					(unit 1)
				)
			)
		)
	)
	(symbol
		(lib_id "antmicroResistors0402:R_330R_0402")
		(at 250.19 236.22 270)
		(unit 1)
		(exclude_from_sim no)
		(in_bom yes)
		(on_board yes)
		(dnp no)
		(fields_autoplaced yes)
		(property "Reference" "R12"
			(at 251.841 237.9294 90)
			(effects
				(font
					(size 1.27 1.27)
				)
				(justify left)
			)
		)
		(property "Value" "R_330R_0402"
			(at 237.49 256.54 0)
			(effects
				(font
					(size 1.27 1.27)
					(thickness 0.15)
				)
				(justify left bottom)
				(hide yes)
			)
		)
		(property "Footprint" "antmicro-footprints:R_0402_1005Metric"
			(at 234.95 256.54 0)
			(effects
				(font
					(size 1.27 1.27)
					(thickness 0.15)
				)
				(justify left bottom)
				(hide yes)
			)
		)
		(property "Datasheet" "https://www.bourns.com/docs/product-datasheets/cr.pdf"
			(at 232.41 256.54 0)
			(effects
				(font
					(size 1.27 1.27)
					(thickness 0.15)
				)
				(justify left bottom)
				(hide yes)
			)
		)
		(property "Description" ""
			(at 250.19 236.22 0)
			(effects
				(font
					(size 1.27 1.27)
				)
			)
		)
		(property "Manufacturer" "Bourns"
			(at 227.33 256.54 0)
			(effects
				(font
					(size 1.27 1.27)
					(thickness 0.15)
				)
				(justify left bottom)
				(hide yes)
			)
		)
		(property "MPN" "CR0402-FX-3300GLF"
			(at 229.87 256.54 0)
			(effects
				(font
					(size 1.27 1.27)
					(thickness 0.15)
				)
				(justify left bottom)
				(hide yes)
			)
		)
		(property "Val" "330R"
			(at 251.841 240.4597 90)
			(effects
				(font
					(size 1.27 1.27)
					(thickness 0.15)
				)
				(justify left)
			)
		)
		(property "License" "Apache-2.0"
			(at 224.79 256.54 0)
			(effects
				(font
					(size 1.27 1.27)
					(thickness 0.15)
				)
				(justify left bottom)
				(hide yes)
			)
		)
		(property "Author" "Antmicro"
			(at 222.25 256.54 0)
			(effects
				(font
					(size 1.27 1.27)
					(thickness 0.15)
				)
				(justify left bottom)
				(hide yes)
			)
		)
		(property "Tolerance" "1%"
			(at 240.03 256.54 0)
			(effects
				(font
					(size 1.27 1.27)
				)
				(justify left bottom)
				(hide yes)
			)
		)
		(pin "1"
		)
		(pin "2"
		)
		(instances
			(project "sodimm-ddr5-tester"
				(path ""
					(reference "R12")
					(unit 1)
				)
			)
		)
	)
	(symbol
		(lib_id "antmicroLEDIndicationDiscrete:LED_G_0603_KP-1608CGCK")
		(at 250.19 227.33 270)
		(unit 1)
		(exclude_from_sim no)
		(in_bom yes)
		(on_board yes)
		(dnp no)
		(property "Reference" "D2"
			(at 253.238 230.3094 90)
			(effects
				(font
					(size 1.27 1.27)
				)
				(justify left)
			)
		)
		(property "Value" "LED_G_0603_KP-1608CGCK"
			(at 265.938 232.664 90)
			(effects
				(font
					(size 1.27 1.27)
					(thickness 0.15)
				)
			)
		)
		(property "Footprint" "antmicro-footprints:LED_0603_1608Metric_G"
			(at 240.03 250.19 0)
			(effects
				(font
					(size 1.27 1.27)
					(thickness 0.15)
				)
				(justify left bottom)
				(hide yes)
			)
		)
		(property "Datasheet" "http://www.farnell.com/datasheets/2045956.pdf"
			(at 237.49 250.19 0)
			(effects
				(font
					(size 1.27 1.27)
					(thickness 0.15)
				)
				(justify left bottom)
				(hide yes)
			)
		)
		(property "Description" ""
			(at 250.19 227.33 0)
			(effects
				(font
					(size 1.27 1.27)
				)
			)
		)
		(property "MPN" "KP-1608CGCK"
			(at 253.238 232.8397 90)
			(effects
				(font
					(size 1.27 1.27)
					(thickness 0.15)
				)
				(justify left)
				(hide yes)
			)
		)
		(property "Manufacturer" "Kingbright"
			(at 232.41 250.19 0)
			(effects
				(font
					(size 1.27 1.27)
					(thickness 0.15)
				)
				(justify left bottom)
				(hide yes)
			)
		)
		(property "Author" "Antmicro"
			(at 229.87 250.19 0)
			(effects
				(font
					(size 1.27 1.27)
					(thickness 0.15)
				)
				(justify left bottom)
				(hide yes)
			)
		)
		(property "License" "Apache-2.0"
			(at 227.33 250.19 0)
			(effects
				(font
					(size 1.27 1.27)
					(thickness 0.15)
				)
				(justify left bottom)
				(hide yes)
			)
		)
		(pin "1"
		)
		(pin "2"
		)
		(instances
			(project "sodimm-ddr5-tester"
				(path ""
					(reference "D2")
					(unit 1)
				)
			)
		)
	)
	(symbol
		(lib_id "antmicropower:GND")
		(at 207.01 256.54 0)
		(unit 1)
		(exclude_from_sim no)
		(in_bom yes)
		(on_board yes)
		(dnp no)
		(property "Reference" "#PWR0174"
			(at 207.01 262.89 0)
			(effects
				(font
					(size 1.27 1.27)
				)
				(hide yes)
			)
		)
		(property "Value" "GND"
			(at 204.978 260.858 0)
			(effects
				(font
					(size 1.27 1.27)
					(thickness 0.15)
				)
				(justify left)
			)
		)
		(property "Footprint" ""
			(at 215.9 264.16 0)
			(effects
				(font
					(size 1.27 1.27)
					(thickness 0.15)
				)
				(justify left bottom)
				(hide yes)
			)
		)
		(property "Datasheet" ""
			(at 215.9 269.24 0)
			(effects
				(font
					(size 1.27 1.27)
					(thickness 0.15)
				)
				(justify left bottom)
				(hide yes)
			)
		)
		(property "Description" ""
			(at 215.9 271.78 0)
			(effects
				(font
					(size 1.27 1.27)
				)
				(justify left bottom)
				(hide yes)
			)
		)
		(property "Author" "Antmicro"
			(at 215.9 264.16 0)
			(effects
				(font
					(size 1.27 1.27)
					(thickness 0.15)
				)
				(justify left bottom)
				(hide yes)
			)
		)
		(property "License" "Apache-2.0"
			(at 215.9 266.7 0)
			(effects
				(font
					(size 1.27 1.27)
					(thickness 0.15)
				)
				(justify left bottom)
				(hide yes)
			)
		)
		(pin "1"
		)
		(instances
			(project "sodimm-ddr5-tester"
				(path ""
					(reference "#PWR0174")
					(unit 1)
				)
			)
		)
	)
	(symbol
		(lib_id "antmicroResistors0402:R_330R_0402")
		(at 207.01 236.22 270)
		(unit 1)
		(exclude_from_sim no)
		(in_bom yes)
		(on_board yes)
		(dnp no)
		(fields_autoplaced yes)
		(property "Reference" "R13"
			(at 208.661 237.9294 90)
			(effects
				(font
					(size 1.27 1.27)
				)
				(justify left)
			)
		)
		(property "Value" "R_330R_0402"
			(at 194.31 256.54 0)
			(effects
				(font
					(size 1.27 1.27)
					(thickness 0.15)
				)
				(justify left bottom)
				(hide yes)
			)
		)
		(property "Footprint" "antmicro-footprints:R_0402_1005Metric"
			(at 191.77 256.54 0)
			(effects
				(font
					(size 1.27 1.27)
					(thickness 0.15)
				)
				(justify left bottom)
				(hide yes)
			)
		)
		(property "Datasheet" "https://www.bourns.com/docs/product-datasheets/cr.pdf"
			(at 189.23 256.54 0)
			(effects
				(font
					(size 1.27 1.27)
					(thickness 0.15)
				)
				(justify left bottom)
				(hide yes)
			)
		)
		(property "Description" ""
			(at 207.01 236.22 0)
			(effects
				(font
					(size 1.27 1.27)
				)
			)
		)
		(property "Manufacturer" "Bourns"
			(at 184.15 256.54 0)
			(effects
				(font
					(size 1.27 1.27)
					(thickness 0.15)
				)
				(justify left bottom)
				(hide yes)
			)
		)
		(property "MPN" "CR0402-FX-3300GLF"
			(at 186.69 256.54 0)
			(effects
				(font
					(size 1.27 1.27)
					(thickness 0.15)
				)
				(justify left bottom)
				(hide yes)
			)
		)
		(property "Val" "330R"
			(at 208.661 240.4597 90)
			(effects
				(font
					(size 1.27 1.27)
					(thickness 0.15)
				)
				(justify left)
			)
		)
		(property "License" "Apache-2.0"
			(at 181.61 256.54 0)
			(effects
				(font
					(size 1.27 1.27)
					(thickness 0.15)
				)
				(justify left bottom)
				(hide yes)
			)
		)
		(property "Author" "Antmicro"
			(at 179.07 256.54 0)
			(effects
				(font
					(size 1.27 1.27)
					(thickness 0.15)
				)
				(justify left bottom)
				(hide yes)
			)
		)
		(property "Tolerance" "1%"
			(at 196.85 256.54 0)
			(effects
				(font
					(size 1.27 1.27)
				)
				(justify left bottom)
				(hide yes)
			)
		)
		(pin "1"
		)
		(pin "2"
		)
		(instances
			(project "sodimm-ddr5-tester"
				(path ""
					(reference "R13")
					(unit 1)
				)
			)
		)
	)
	(symbol
		(lib_id "antmicroLEDIndicationDiscrete:LED_G_0603_KP-1608CGCK")
		(at 207.01 227.33 270)
		(unit 1)
		(exclude_from_sim no)
		(in_bom yes)
		(on_board yes)
		(dnp no)
		(property "Reference" "D3"
			(at 210.058 230.3094 90)
			(effects
				(font
					(size 1.27 1.27)
				)
				(justify left)
			)
		)
		(property "Value" "LED_G_0603_KP-1608CGCK"
			(at 223.393 232.664 90)
			(effects
				(font
					(size 1.27 1.27)
					(thickness 0.15)
				)
			)
		)
		(property "Footprint" "antmicro-footprints:LED_0603_1608Metric_G"
			(at 196.85 250.19 0)
			(effects
				(font
					(size 1.27 1.27)
					(thickness 0.15)
				)
				(justify left bottom)
				(hide yes)
			)
		)
		(property "Datasheet" "http://www.farnell.com/datasheets/2045956.pdf"
			(at 194.31 250.19 0)
			(effects
				(font
					(size 1.27 1.27)
					(thickness 0.15)
				)
				(justify left bottom)
				(hide yes)
			)
		)
		(property "Description" ""
			(at 207.01 227.33 0)
			(effects
				(font
					(size 1.27 1.27)
				)
			)
		)
		(property "MPN" "KP-1608CGCK"
			(at 210.058 232.8397 90)
			(effects
				(font
					(size 1.27 1.27)
					(thickness 0.15)
				)
				(justify left)
				(hide yes)
			)
		)
		(property "Manufacturer" "Kingbright"
			(at 189.23 250.19 0)
			(effects
				(font
					(size 1.27 1.27)
					(thickness 0.15)
				)
				(justify left bottom)
				(hide yes)
			)
		)
		(property "Author" "Antmicro"
			(at 186.69 250.19 0)
			(effects
				(font
					(size 1.27 1.27)
					(thickness 0.15)
				)
				(justify left bottom)
				(hide yes)
			)
		)
		(property "License" "Apache-2.0"
			(at 184.15 250.19 0)
			(effects
				(font
					(size 1.27 1.27)
					(thickness 0.15)
				)
				(justify left bottom)
				(hide yes)
			)
		)
		(pin "1"
		)
		(pin "2"
		)
		(instances
			(project "sodimm-ddr5-tester"
				(path ""
					(reference "D3")
					(unit 1)
				)
			)
		)
	)
	(symbol
		(lib_id "antmicropower:GND")
		(at 171.45 133.35 0)
		(unit 1)
		(exclude_from_sim no)
		(in_bom yes)
		(on_board yes)
		(dnp no)
		(property "Reference" "#PWR0187"
			(at 171.45 139.7 0)
			(effects
				(font
					(size 1.27 1.27)
				)
				(hide yes)
			)
		)
		(property "Value" "GND"
			(at 169.418 137.668 0)
			(effects
				(font
					(size 1.27 1.27)
					(thickness 0.15)
				)
				(justify left)
			)
		)
		(property "Footprint" ""
			(at 180.34 140.97 0)
			(effects
				(font
					(size 1.27 1.27)
					(thickness 0.15)
				)
				(justify left bottom)
				(hide yes)
			)
		)
		(property "Datasheet" ""
			(at 180.34 146.05 0)
			(effects
				(font
					(size 1.27 1.27)
					(thickness 0.15)
				)
				(justify left bottom)
				(hide yes)
			)
		)
		(property "Description" ""
			(at 180.34 148.59 0)
			(effects
				(font
					(size 1.27 1.27)
				)
				(justify left bottom)
				(hide yes)
			)
		)
		(property "Author" "Antmicro"
			(at 180.34 140.97 0)
			(effects
				(font
					(size 1.27 1.27)
					(thickness 0.15)
				)
				(justify left bottom)
				(hide yes)
			)
		)
		(property "License" "Apache-2.0"
			(at 180.34 143.51 0)
			(effects
				(font
					(size 1.27 1.27)
					(thickness 0.15)
				)
				(justify left bottom)
				(hide yes)
			)
		)
		(pin "1"
		)
		(instances
			(project "sodimm-ddr5-tester"
				(path ""
					(reference "#PWR0187")
					(unit 1)
				)
			)
		)
	)
	(symbol
		(lib_id "antmicroResistors0402:R_0R_0402")
		(at 248.285 76.835 90)
		(mirror x)
		(unit 1)
		(exclude_from_sim no)
		(in_bom yes)
		(on_board yes)
		(dnp no)
		(fields_autoplaced yes)
		(property "Reference" "R20"
			(at 250.825 78.105 90)
			(effects
				(font
					(size 1.27 1.27)
				)
				(justify right)
			)
		)
		(property "Value" "R_0R_0402"
			(at 260.985 97.155 0)
			(effects
				(font
					(size 1.27 1.27)
					(thickness 0.15)
				)
				(justify left bottom)
				(hide yes)
			)
		)
		(property "Footprint" "antmicro-footprints:R_0402_1005Metric"
			(at 263.525 97.155 0)
			(effects
				(font
					(size 1.27 1.27)
					(thickness 0.15)
				)
				(justify left bottom)
				(hide yes)
			)
		)
		(property "Datasheet" "https://industrial.panasonic.com/cdbs/www-data/pdf/RDA0000/AOA0000C301.pdf"
			(at 266.065 97.155 0)
			(effects
				(font
					(size 1.27 1.27)
					(thickness 0.15)
				)
				(justify left bottom)
				(hide yes)
			)
		)
		(property "Description" ""
			(at 248.285 76.835 0)
			(effects
				(font
					(size 1.27 1.27)
				)
			)
		)
		(property "Manufacturer" "Panasonic"
			(at 271.145 97.155 0)
			(effects
				(font
					(size 1.27 1.27)
					(thickness 0.15)
				)
				(justify left bottom)
				(hide yes)
			)
		)
		(property "MPN" "ERJ2GE0R00X"
			(at 268.605 97.155 0)
			(effects
				(font
					(size 1.27 1.27)
					(thickness 0.15)
				)
				(justify left bottom)
				(hide yes)
			)
		)
		(property "Val" "0R"
			(at 250.825 81.2799 90)
			(effects
				(font
					(size 1.27 1.27)
					(thickness 0.15)
				)
				(justify right)
			)
		)
		(property "License" "Apache-2.0"
			(at 273.685 97.155 0)
			(effects
				(font
					(size 1.27 1.27)
					(thickness 0.15)
				)
				(justify left bottom)
				(hide yes)
			)
		)
		(property "Author" "Antmicro"
			(at 276.225 97.155 0)
			(effects
				(font
					(size 1.27 1.27)
					(thickness 0.15)
				)
				(justify left bottom)
				(hide yes)
			)
		)
		(property "Tolerance" "~"
			(at 258.445 97.155 0)
			(effects
				(font
					(size 1.27 1.27)
				)
				(justify left bottom)
				(hide yes)
			)
		)
		(property "Current" "1A"
			(at 278.765 97.155 0)
			(effects
				(font
					(size 1.27 1.27)
					(thickness 0.15)
				)
				(justify left bottom)
				(hide yes)
			)
		)
		(pin "1"
		)
		(pin "2"
		)
		(instances
			(project "sodimm-ddr5-tester"
				(path ""
					(reference "R20")
					(unit 1)
				)
			)
		)
	)
	(symbol
		(lib_id "antmicroFPGAChips:XC7K160T-FFG676")
		(at 204.47 78.74 0)
		(unit 11)
		(exclude_from_sim no)
		(in_bom yes)
		(on_board yes)
		(dnp no)
		(fields_autoplaced yes)
		(property "Reference" "U4"
			(at 222.25 72.5084 0)
			(effects
				(font
					(size 1.27 1.27)
				)
			)
		)
		(property "Value" "XC7K160T-FFG676"
			(at 222.25 75.0387 0)
			(effects
				(font
					(size 1.27 1.27)
					(thickness 0.15)
				)
			)
		)
		(property "Footprint" "antmicro-footprints:BGA-676_27x27mm_Layout26x26_P1x1mm_FFG676"
			(at 273.05 81.28 0)
			(effects
				(font
					(size 1.27 1.27)
					(thickness 0.15)
				)
				(justify left bottom)
				(hide yes)
			)
		)
		(property "Datasheet" "https://docs.xilinx.com/v/u/en-US/ds180_7Series_Overview"
			(at 273.05 83.82 0)
			(effects
				(font
					(size 1.27 1.27)
					(thickness 0.15)
				)
				(justify left bottom)
				(hide yes)
			)
		)
		(property "Description" ""
			(at 204.47 78.74 0)
			(effects
				(font
					(size 1.27 1.27)
				)
			)
		)
		(property "MPN" "XC7K160T-FFG676"
			(at 204.47 78.74 0)
			(effects
				(font
					(size 1.27 1.27)
				)
				(hide yes)
			)
		)
		(property "Author" "Antmicro"
			(at 273.05 86.36 0)
			(effects
				(font
					(size 1.27 1.27)
					(thickness 0.15)
				)
				(justify left bottom)
				(hide yes)
			)
		)
		(property "License" "Apache-2.0"
			(at 273.05 88.9 0)
			(effects
				(font
					(size 1.27 1.27)
					(thickness 0.15)
				)
				(justify left bottom)
				(hide yes)
			)
		)
		(property "Manufacturer" "AMD-Xilinx"
			(at 204.47 78.74 0)
			(effects
				(font
					(size 1.27 1.27)
				)
				(hide yes)
			)
		)
		(pin "AA21"
		)
		(pin "AA22"
		)
		(pin "AA23"
		)
		(pin "AA24"
		)
		(pin "AA25"
		)
		(pin "AB21"
		)
		(pin "AB22"
		)
		(pin "AB24"
		)
		(pin "AB25"
		)
		(pin "AB26"
		)
		(pin "AC21"
		)
		(pin "AC22"
		)
		(pin "AC23"
		)
		(pin "AC24"
		)
		(pin "AC25"
		)
		(pin "AC26"
		)
		(pin "AD21"
		)
		(pin "AD22"
		)
		(pin "AD23"
		)
		(pin "AD24"
		)
		(pin "AD25"
		)
		(pin "AD26"
		)
		(pin "AE21"
		)
		(pin "AE22"
		)
		(pin "AE23"
		)
		(pin "AE25"
		)
		(pin "AE26"
		)
		(pin "AF22"
		)
		(pin "AF23"
		)
		(pin "AF24"
		)
		(pin "AF25"
		)
		(pin "AF26"
		)
		(pin "U21"
		)
		(pin "U22"
		)
		(pin "U23"
		)
		(pin "U24"
		)
		(pin "U25"
		)
		(pin "U26"
		)
		(pin "V20"
		)
		(pin "V21"
		)
		(pin "V22"
		)
		(pin "V23"
		)
		(pin "V24"
		)
		(pin "V26"
		)
		(pin "W20"
		)
		(pin "W21"
		)
		(pin "W23"
		)
		(pin "W24"
		)
		(pin "W25"
		)
		(pin "W26"
		)
		(pin "Y20"
		)
		(pin "Y21"
		)
		(pin "Y22"
		)
		(pin "Y23"
		)
		(pin "Y24"
		)
		(pin "Y25"
		)
		(pin "Y26"
		)
		(pin "K24"
		)
		(pin "K25"
		)
		(pin "K26"
		)
		(pin "L24"
		)
		(pin "L25"
		)
		(pin "M19"
		)
		(pin "M20"
		)
		(pin "M21"
		)
		(pin "M22"
		)
		(pin "M24"
		)
		(pin "M25"
		)
		(pin "M26"
		)
		(pin "N16"
		)
		(pin "N17"
		)
		(pin "N18"
		)
		(pin "N19"
		)
		(pin "N21"
		)
		(pin "N22"
		)
		(pin "N23"
		)
		(pin "N24"
		)
		(pin "N25"
		)
		(pin "N26"
		)
		(pin "P16"
		)
		(pin "P18"
		)
		(pin "P19"
		)
		(pin "P20"
		)
		(pin "P21"
		)
		(pin "P22"
		)
		(pin "P23"
		)
		(pin "P24"
		)
		(pin "P25"
		)
		(pin "P26"
		)
		(pin "R16"
		)
		(pin "R17"
		)
		(pin "R18"
		)
		(pin "R19"
		)
		(pin "R20"
		)
		(pin "R21"
		)
		(pin "R22"
		)
		(pin "R23"
		)
		(pin "R25"
		)
		(pin "R26"
		)
		(pin "T16"
		)
		(pin "T17"
		)
		(pin "T18"
		)
		(pin "T19"
		)
		(pin "T20"
		)
		(pin "T22"
		)
		(pin "T23"
		)
		(pin "T24"
		)
		(pin "T25"
		)
		(pin "T26"
		)
		(pin "U16"
		)
		(pin "U17"
		)
		(pin "U19"
		)
		(pin "U20"
		)
		(pin "A20"
		)
		(pin "A21"
		)
		(pin "A22"
		)
		(pin "A23"
		)
		(pin "A24"
		)
		(pin "A25"
		)
		(pin "B20"
		)
		(pin "B21"
		)
		(pin "B22"
		)
		(pin "B24"
		)
		(pin "B25"
		)
		(pin "B26"
		)
		(pin "C21"
		)
		(pin "C22"
		)
		(pin "C23"
		)
		(pin "C24"
		)
		(pin "C25"
		)
		(pin "C26"
		)
		(pin "D21"
		)
		(pin "D22"
		)
		(pin "D23"
		)
		(pin "D24"
		)
		(pin "D25"
		)
		(pin "D26"
		)
		(pin "E21"
		)
		(pin "E22"
		)
		(pin "E23"
		)
		(pin "E25"
		)
		(pin "E26"
		)
		(pin "F22"
		)
		(pin "F23"
		)
		(pin "F24"
		)
		(pin "F25"
		)
		(pin "F26"
		)
		(pin "G21"
		)
		(pin "G22"
		)
		(pin "G23"
		)
		(pin "G24"
		)
		(pin "G25"
		)
		(pin "G26"
		)
		(pin "H21"
		)
		(pin "H22"
		)
		(pin "H23"
		)
		(pin "H24"
		)
		(pin "H26"
		)
		(pin "J21"
		)
		(pin "J23"
		)
		(pin "J24"
		)
		(pin "J25"
		)
		(pin "J26"
		)
		(pin "K21"
		)
		(pin "K22"
		)
		(pin "K23"
		)
		(pin "L21"
		)
		(pin "L22"
		)
		(pin "L23"
		)
		(pin "A17"
		)
		(pin "A18"
		)
		(pin "A19"
		)
		(pin "B16"
		)
		(pin "B17"
		)
		(pin "B18"
		)
		(pin "B19"
		)
		(pin "C16"
		)
		(pin "C17"
		)
		(pin "C18"
		)
		(pin "C19"
		)
		(pin "D15"
		)
		(pin "D16"
		)
		(pin "D18"
		)
		(pin "D19"
		)
		(pin "D20"
		)
		(pin "E15"
		)
		(pin "E16"
		)
		(pin "E17"
		)
		(pin "E18"
		)
		(pin "E19"
		)
		(pin "E20"
		)
		(pin "F15"
		)
		(pin "F16"
		)
		(pin "F17"
		)
		(pin "F18"
		)
		(pin "F19"
		)
		(pin "F20"
		)
		(pin "G15"
		)
		(pin "G16"
		)
		(pin "G17"
		)
		(pin "G19"
		)
		(pin "G20"
		)
		(pin "H16"
		)
		(pin "H17"
		)
		(pin "H18"
		)
		(pin "H19"
		)
		(pin "H20"
		)
		(pin "J15"
		)
		(pin "J16"
		)
		(pin "J17"
		)
		(pin "J18"
		)
		(pin "J19"
		)
		(pin "J20"
		)
		(pin "K15"
		)
		(pin "K16"
		)
		(pin "K17"
		)
		(pin "K18"
		)
		(pin "K20"
		)
		(pin "L17"
		)
		(pin "L18"
		)
		(pin "L19"
		)
		(pin "L20"
		)
		(pin "M16"
		)
		(pin "M17"
		)
		(pin "M18"
		)
		(pin "A10"
		)
		(pin "A11"
		)
		(pin "A12"
		)
		(pin "A13"
		)
		(pin "A14"
		)
		(pin "A15"
		)
		(pin "A8"
		)
		(pin "A9"
		)
		(pin "B10"
		)
		(pin "B11"
		)
		(pin "B12"
		)
		(pin "B14"
		)
		(pin "B15"
		)
		(pin "B8"
		)
		(pin "B9"
		)
		(pin "C11"
		)
		(pin "C12"
		)
		(pin "C13"
		)
		(pin "C14"
		)
		(pin "C15"
		)
		(pin "C9"
		)
		(pin "D10"
		)
		(pin "D11"
		)
		(pin "D12"
		)
		(pin "D13"
		)
		(pin "D14"
		)
		(pin "D8"
		)
		(pin "D9"
		)
		(pin "E10"
		)
		(pin "E11"
		)
		(pin "E12"
		)
		(pin "E13"
		)
		(pin "E9"
		)
		(pin "F10"
		)
		(pin "F12"
		)
		(pin "F13"
		)
		(pin "F14"
		)
		(pin "F8"
		)
		(pin "F9"
		)
		(pin "G10"
		)
		(pin "G11"
		)
		(pin "G12"
		)
		(pin "G13"
		)
		(pin "G14"
		)
		(pin "G9"
		)
		(pin "H10"
		)
		(pin "H11"
		)
		(pin "H12"
		)
		(pin "H13"
		)
		(pin "H14"
		)
		(pin "H8"
		)
		(pin "H9"
		)
		(pin "J10"
		)
		(pin "J11"
		)
		(pin "J13"
		)
		(pin "J14"
		)
		(pin "J8"
		)
		(pin "AA14"
		)
		(pin "AA15"
		)
		(pin "AA17"
		)
		(pin "AA18"
		)
		(pin "AA19"
		)
		(pin "AA20"
		)
		(pin "AB14"
		)
		(pin "AB15"
		)
		(pin "AB16"
		)
		(pin "AB17"
		)
		(pin "AB18"
		)
		(pin "AB19"
		)
		(pin "AB20"
		)
		(pin "AC14"
		)
		(pin "AC15"
		)
		(pin "AC16"
		)
		(pin "AC17"
		)
		(pin "AC18"
		)
		(pin "AC19"
		)
		(pin "AD14"
		)
		(pin "AD15"
		)
		(pin "AD16"
		)
		(pin "AD18"
		)
		(pin "AD19"
		)
		(pin "AD20"
		)
		(pin "AE15"
		)
		(pin "AE16"
		)
		(pin "AE17"
		)
		(pin "AE18"
		)
		(pin "AE19"
		)
		(pin "AE20"
		)
		(pin "AF14"
		)
		(pin "AF15"
		)
		(pin "AF16"
		)
		(pin "AF17"
		)
		(pin "AF18"
		)
		(pin "AF19"
		)
		(pin "AF20"
		)
		(pin "V13"
		)
		(pin "V14"
		)
		(pin "V16"
		)
		(pin "V17"
		)
		(pin "V18"
		)
		(pin "V19"
		)
		(pin "W13"
		)
		(pin "W14"
		)
		(pin "W15"
		)
		(pin "W16"
		)
		(pin "W17"
		)
		(pin "W18"
		)
		(pin "W19"
		)
		(pin "Y14"
		)
		(pin "Y15"
		)
		(pin "Y16"
		)
		(pin "Y17"
		)
		(pin "Y18"
		)
		(pin "AA10"
		)
		(pin "AA11"
		)
		(pin "AA12"
		)
		(pin "AA13"
		)
		(pin "AA7"
		)
		(pin "AA8"
		)
		(pin "AA9"
		)
		(pin "AB10"
		)
		(pin "AB11"
		)
		(pin "AB12"
		)
		(pin "AB7"
		)
		(pin "AB8"
		)
		(pin "AB9"
		)
		(pin "AC11"
		)
		(pin "AC12"
		)
		(pin "AC13"
		)
		(pin "AC7"
		)
		(pin "AC8"
		)
		(pin "AC9"
		)
		(pin "AD10"
		)
		(pin "AD11"
		)
		(pin "AD12"
		)
		(pin "AD13"
		)
		(pin "AD8"
		)
		(pin "AD9"
		)
		(pin "AE10"
		)
		(pin "AE11"
		)
		(pin "AE12"
		)
		(pin "AE13"
		)
		(pin "AE7"
		)
		(pin "AE8"
		)
		(pin "AE9"
		)
		(pin "AF10"
		)
		(pin "AF12"
		)
		(pin "AF13"
		)
		(pin "AF7"
		)
		(pin "AF8"
		)
		(pin "AF9"
		)
		(pin "U9"
		)
		(pin "V10"
		)
		(pin "V11"
		)
		(pin "V12"
		)
		(pin "V7"
		)
		(pin "V8"
		)
		(pin "V9"
		)
		(pin "W10"
		)
		(pin "W11"
		)
		(pin "W7"
		)
		(pin "W8"
		)
		(pin "W9"
		)
		(pin "Y10"
		)
		(pin "Y11"
		)
		(pin "Y12"
		)
		(pin "Y13"
		)
		(pin "Y7"
		)
		(pin "Y8"
		)
		(pin "AA1"
		)
		(pin "AA2"
		)
		(pin "AA3"
		)
		(pin "AA4"
		)
		(pin "AA5"
		)
		(pin "AB1"
		)
		(pin "AB2"
		)
		(pin "AB4"
		)
		(pin "AB5"
		)
		(pin "AB6"
		)
		(pin "AC1"
		)
		(pin "AC2"
		)
		(pin "AC3"
		)
		(pin "AC4"
		)
		(pin "AC5"
		)
		(pin "AC6"
		)
		(pin "AD1"
		)
		(pin "AD2"
		)
		(pin "AD3"
		)
		(pin "AD4"
		)
		(pin "AD5"
		)
		(pin "AD6"
		)
		(pin "AE1"
		)
		(pin "AE2"
		)
		(pin "AE3"
		)
		(pin "AE5"
		)
		(pin "AE6"
		)
		(pin "AF2"
		)
		(pin "AF3"
		)
		(pin "AF4"
		)
		(pin "AF5"
		)
		(pin "AF6"
		)
		(pin "T7"
		)
		(pin "U1"
		)
		(pin "U2"
		)
		(pin "U3"
		)
		(pin "U4"
		)
		(pin "U5"
		)
		(pin "U6"
		)
		(pin "U7"
		)
		(pin "V1"
		)
		(pin "V2"
		)
		(pin "V3"
		)
		(pin "V4"
		)
		(pin "V6"
		)
		(pin "W1"
		)
		(pin "W3"
		)
		(pin "W4"
		)
		(pin "W5"
		)
		(pin "W6"
		)
		(pin "Y1"
		)
		(pin "Y2"
		)
		(pin "Y3"
		)
		(pin "Y4"
		)
		(pin "Y5"
		)
		(pin "Y6"
		)
		(pin "A3"
		)
		(pin "A4"
		)
		(pin "B1"
		)
		(pin "B2"
		)
		(pin "B5"
		)
		(pin "B6"
		)
		(pin "C3"
		)
		(pin "C4"
		)
		(pin "D1"
		)
		(pin "D2"
		)
		(pin "D5"
		)
		(pin "D6"
		)
		(pin "E3"
		)
		(pin "E4"
		)
		(pin "F1"
		)
		(pin "F2"
		)
		(pin "F5"
		)
		(pin "F6"
		)
		(pin "G3"
		)
		(pin "G4"
		)
		(pin "H1"
		)
		(pin "H2"
		)
		(pin "H5"
		)
		(pin "H6"
		)
		(pin "J3"
		)
		(pin "J4"
		)
		(pin "K1"
		)
		(pin "K2"
		)
		(pin "K5"
		)
		(pin "K6"
		)
		(pin "L3"
		)
		(pin "L4"
		)
		(pin "M1"
		)
		(pin "M2"
		)
		(pin "N3"
		)
		(pin "N4"
		)
		(pin "P1"
		)
		(pin "P2"
		)
		(pin "R3"
		)
		(pin "R4"
		)
		(pin "A1"
		)
		(pin "A16"
		)
		(pin "A2"
		)
		(pin "A26"
		)
		(pin "A5"
		)
		(pin "A6"
		)
		(pin "A7"
		)
		(pin "AA16"
		)
		(pin "AA26"
		)
		(pin "AA6"
		)
		(pin "AB13"
		)
		(pin "AB23"
		)
		(pin "AB3"
		)
		(pin "AC10"
		)
		(pin "AC20"
		)
		(pin "AD17"
		)
		(pin "AD7"
		)
		(pin "AE14"
		)
		(pin "AE24"
		)
		(pin "AE4"
		)
		(pin "AF1"
		)
		(pin "AF11"
		)
		(pin "AF21"
		)
		(pin "B13"
		)
		(pin "B23"
		)
		(pin "B3"
		)
		(pin "B4"
		)
		(pin "B7"
		)
		(pin "C1"
		)
		(pin "C10"
		)
		(pin "C2"
		)
		(pin "C20"
		)
		(pin "C5"
		)
		(pin "C6"
		)
		(pin "C7"
		)
		(pin "D17"
		)
		(pin "D3"
		)
		(pin "D4"
		)
		(pin "D7"
		)
		(pin "E1"
		)
		(pin "E14"
		)
		(pin "E2"
		)
		(pin "E24"
		)
		(pin "E5"
		)
		(pin "E6"
		)
		(pin "E7"
		)
		(pin "E8"
		)
		(pin "F11"
		)
		(pin "F21"
		)
		(pin "F3"
		)
		(pin "F4"
		)
		(pin "F7"
		)
		(pin "G1"
		)
		(pin "G18"
		)
		(pin "G2"
		)
		(pin "G5"
		)
		(pin "G6"
		)
		(pin "G8"
		)
		(pin "H15"
		)
		(pin "H25"
		)
		(pin "H3"
		)
		(pin "H4"
		)
		(pin "H7"
		)
		(pin "J1"
		)
		(pin "J12"
		)
		(pin "J2"
		)
		(pin "J22"
		)
		(pin "J5"
		)
		(pin "J6"
		)
		(pin "J9"
		)
		(pin "K10"
		)
		(pin "K11"
		)
		(pin "K12"
		)
		(pin "K13"
		)
		(pin "K14"
		)
		(pin "K19"
		)
		(pin "K3"
		)
		(pin "K4"
		)
		(pin "K7"
		)
		(pin "K8"
		)
		(pin "K9"
		)
		(pin "L1"
		)
		(pin "L10"
		)
		(pin "L11"
		)
		(pin "L12"
		)
		(pin "L13"
		)
		(pin "L14"
		)
		(pin "L15"
		)
		(pin "L16"
		)
		(pin "L2"
		)
		(pin "L26"
		)
		(pin "L5"
		)
		(pin "L6"
		)
		(pin "L9"
		)
		(pin "M10"
		)
		(pin "M11"
		)
		(pin "M12"
		)
		(pin "M13"
		)
		(pin "M14"
		)
		(pin "M15"
		)
		(pin "M23"
		)
		(pin "M3"
		)
		(pin "M4"
		)
		(pin "M5"
		)
		(pin "M6"
		)
		(pin "M7"
		)
		(pin "M8"
		)
		(pin "M9"
		)
		(pin "N1"
		)
		(pin "N10"
		)
		(pin "N13"
		)
		(pin "N14"
		)
		(pin "N15"
		)
		(pin "N2"
		)
		(pin "N20"
		)
		(pin "N5"
		)
		(pin "N6"
		)
		(pin "N7"
		)
		(pin "N9"
		)
		(pin "P10"
		)
		(pin "P13"
		)
		(pin "P14"
		)
		(pin "P15"
		)
		(pin "P17"
		)
		(pin "P3"
		)
		(pin "P4"
		)
		(pin "P8"
		)
		(pin "P9"
		)
		(pin "R1"
		)
		(pin "R10"
		)
		(pin "R13"
		)
		(pin "R14"
		)
		(pin "R15"
		)
		(pin "R2"
		)
		(pin "R24"
		)
		(pin "R5"
		)
		(pin "R8"
		)
		(pin "R9"
		)
		(pin "T1"
		)
		(pin "T10"
		)
		(pin "T11"
		)
		(pin "T12"
		)
		(pin "T13"
		)
		(pin "T14"
		)
		(pin "T15"
		)
		(pin "T21"
		)
		(pin "T3"
		)
		(pin "T4"
		)
		(pin "T8"
		)
		(pin "T9"
		)
		(pin "U10"
		)
		(pin "U11"
		)
		(pin "U12"
		)
		(pin "U13"
		)
		(pin "U14"
		)
		(pin "U15"
		)
		(pin "U18"
		)
		(pin "U8"
		)
		(pin "V15"
		)
		(pin "V25"
		)
		(pin "V5"
		)
		(pin "W12"
		)
		(pin "W2"
		)
		(pin "W22"
		)
		(pin "Y19"
		)
		(pin "Y9"
		)
		(pin "C8"
		)
		(pin "G7"
		)
		(pin "J7"
		)
		(pin "L7"
		)
		(pin "L8"
		)
		(pin "N11"
		)
		(pin "N12"
		)
		(pin "N8"
		)
		(pin "P11"
		)
		(pin "P12"
		)
		(pin "P5"
		)
		(pin "P6"
		)
		(pin "P7"
		)
		(pin "R11"
		)
		(pin "R12"
		)
		(pin "R6"
		)
		(pin "R7"
		)
		(pin "T2"
		)
		(pin "T5"
		)
		(pin "T6"
		)
		(instances
			(project "sodimm-ddr5-tester"
				(path ""
					(reference "U4")
					(unit 11)
				)
			)
		)
	)
	(symbol
		(lib_id "antmicropower:GND")
		(at 243.205 118.745 0)
		(mirror y)
		(unit 1)
		(exclude_from_sim no)
		(in_bom yes)
		(on_board yes)
		(dnp no)
		(property "Reference" "#PWR0179"
			(at 243.205 125.095 0)
			(effects
				(font
					(size 1.27 1.27)
				)
				(hide yes)
			)
		)
		(property "Value" "GND"
			(at 241.3 122.682 0)
			(effects
				(font
					(size 1.27 1.27)
					(thickness 0.15)
				)
				(justify right)
			)
		)
		(property "Footprint" ""
			(at 234.315 126.365 0)
			(effects
				(font
					(size 1.27 1.27)
					(thickness 0.15)
				)
				(justify left bottom)
				(hide yes)
			)
		)
		(property "Datasheet" ""
			(at 234.315 131.445 0)
			(effects
				(font
					(size 1.27 1.27)
					(thickness 0.15)
				)
				(justify left bottom)
				(hide yes)
			)
		)
		(property "Description" ""
			(at 234.315 133.985 0)
			(effects
				(font
					(size 1.27 1.27)
				)
				(justify left bottom)
				(hide yes)
			)
		)
		(property "Author" "Antmicro"
			(at 234.315 126.365 0)
			(effects
				(font
					(size 1.27 1.27)
					(thickness 0.15)
				)
				(justify left bottom)
				(hide yes)
			)
		)
		(property "License" "Apache-2.0"
			(at 234.315 128.905 0)
			(effects
				(font
					(size 1.27 1.27)
					(thickness 0.15)
				)
				(justify left bottom)
				(hide yes)
			)
		)
		(pin "1"
		)
		(instances
			(project "sodimm-ddr5-tester"
				(path ""
					(reference "#PWR0179")
					(unit 1)
				)
			)
		)
	)
	(symbol
		(lib_id "antmicroResistors0402:R_4k7_0402")
		(at 163.195 99.695 270)
		(unit 1)
		(exclude_from_sim no)
		(in_bom yes)
		(on_board yes)
		(dnp no)
		(property "Reference" "R16"
			(at 163.83 99.0601 90)
			(effects
				(font
					(size 1.27 1.27)
				)
				(justify left)
			)
		)
		(property "Value" "R_4k7_0402"
			(at 150.495 120.015 0)
			(effects
				(font
					(size 1.27 1.27)
					(thickness 0.15)
				)
				(justify left bottom)
				(hide yes)
			)
		)
		(property "Footprint" "antmicro-footprints:R_0402_1005Metric"
			(at 147.955 120.015 0)
			(effects
				(font
					(size 1.27 1.27)
					(thickness 0.15)
				)
				(justify left bottom)
				(hide yes)
			)
		)
		(property "Datasheet" "https://www.bourns.com/docs/product-datasheets/cr.pdf"
			(at 145.415 120.015 0)
			(effects
				(font
					(size 1.27 1.27)
					(thickness 0.15)
				)
				(justify left bottom)
				(hide yes)
			)
		)
		(property "Description" ""
			(at 163.195 99.695 0)
			(effects
				(font
					(size 1.27 1.27)
				)
			)
		)
		(property "Manufacturer" "Bourns"
			(at 140.335 120.015 0)
			(effects
				(font
					(size 1.27 1.27)
					(thickness 0.15)
				)
				(justify left bottom)
				(hide yes)
			)
		)
		(property "MPN" "CR0402-FX-4701GLF"
			(at 142.875 120.015 0)
			(effects
				(font
					(size 1.27 1.27)
					(thickness 0.15)
				)
				(justify left bottom)
				(hide yes)
			)
		)
		(property "Val" "4k7"
			(at 165.1 104.14 90)
			(effects
				(font
					(size 1.27 1.27)
					(thickness 0.15)
				)
				(justify left)
			)
		)
		(property "License" "Apache-2.0"
			(at 137.795 120.015 0)
			(effects
				(font
					(size 1.27 1.27)
					(thickness 0.15)
				)
				(justify left bottom)
				(hide yes)
			)
		)
		(property "Author" "Antmicro"
			(at 135.255 120.015 0)
			(effects
				(font
					(size 1.27 1.27)
					(thickness 0.15)
				)
				(justify left bottom)
				(hide yes)
			)
		)
		(property "Tolerance" "1%"
			(at 153.035 120.015 0)
			(effects
				(font
					(size 1.27 1.27)
				)
				(justify left bottom)
				(hide yes)
			)
		)
		(pin "1"
		)
		(pin "2"
		)
		(instances
			(project "sodimm-ddr5-tester"
				(path ""
					(reference "R16")
					(unit 1)
				)
			)
		)
	)
	(symbol
		(lib_id "antmicroResistors0402:R_330R_0402")
		(at 165.1 236.22 270)
		(unit 1)
		(exclude_from_sim no)
		(in_bom yes)
		(on_board yes)
		(dnp no)
		(fields_autoplaced yes)
		(property "Reference" "R11"
			(at 166.751 237.9294 90)
			(effects
				(font
					(size 1.27 1.27)
				)
				(justify left)
			)
		)
		(property "Value" "R_330R_0402"
			(at 152.4 256.54 0)
			(effects
				(font
					(size 1.27 1.27)
					(thickness 0.15)
				)
				(justify left bottom)
				(hide yes)
			)
		)
		(property "Footprint" "antmicro-footprints:R_0402_1005Metric"
			(at 149.86 256.54 0)
			(effects
				(font
					(size 1.27 1.27)
					(thickness 0.15)
				)
				(justify left bottom)
				(hide yes)
			)
		)
		(property "Datasheet" "https://www.bourns.com/docs/product-datasheets/cr.pdf"
			(at 147.32 256.54 0)
			(effects
				(font
					(size 1.27 1.27)
					(thickness 0.15)
				)
				(justify left bottom)
				(hide yes)
			)
		)
		(property "Description" ""
			(at 165.1 236.22 0)
			(effects
				(font
					(size 1.27 1.27)
				)
			)
		)
		(property "Manufacturer" "Bourns"
			(at 142.24 256.54 0)
			(effects
				(font
					(size 1.27 1.27)
					(thickness 0.15)
				)
				(justify left bottom)
				(hide yes)
			)
		)
		(property "MPN" "CR0402-FX-3300GLF"
			(at 144.78 256.54 0)
			(effects
				(font
					(size 1.27 1.27)
					(thickness 0.15)
				)
				(justify left bottom)
				(hide yes)
			)
		)
		(property "Val" "330R"
			(at 166.751 240.4597 90)
			(effects
				(font
					(size 1.27 1.27)
					(thickness 0.15)
				)
				(justify left)
			)
		)
		(property "License" "Apache-2.0"
			(at 139.7 256.54 0)
			(effects
				(font
					(size 1.27 1.27)
					(thickness 0.15)
				)
				(justify left bottom)
				(hide yes)
			)
		)
		(property "Author" "Antmicro"
			(at 137.16 256.54 0)
			(effects
				(font
					(size 1.27 1.27)
					(thickness 0.15)
				)
				(justify left bottom)
				(hide yes)
			)
		)
		(property "Tolerance" "1%"
			(at 154.94 256.54 0)
			(effects
				(font
					(size 1.27 1.27)
				)
				(justify left bottom)
				(hide yes)
			)
		)
		(pin "1"
		)
		(pin "2"
		)
		(instances
			(project "sodimm-ddr5-tester"
				(path ""
					(reference "R11")
					(unit 1)
				)
			)
		)
	)
	(symbol
		(lib_id "antmicropower:+3V3")
		(at 203.2 76.835 0)
		(unit 1)
		(exclude_from_sim no)
		(in_bom yes)
		(on_board yes)
		(dnp no)
		(property "Reference" "#PWR0180"
			(at 203.2 80.645 0)
			(effects
				(font
					(size 1.27 1.27)
				)
				(hide yes)
			)
		)
		(property "Value" "+3V3"
			(at 200.025 74.295 0)
			(effects
				(font
					(size 1.27 1.27)
					(thickness 0.15)
				)
				(justify left bottom)
			)
		)
		(property "Footprint" ""
			(at 218.44 84.455 0)
			(effects
				(font
					(size 1.27 1.27)
					(thickness 0.15)
				)
				(justify left bottom)
				(hide yes)
			)
		)
		(property "Datasheet" ""
			(at 218.44 86.995 0)
			(effects
				(font
					(size 1.27 1.27)
					(thickness 0.15)
				)
				(justify left bottom)
				(hide yes)
			)
		)
		(property "Description" ""
			(at 203.2 76.835 0)
			(effects
				(font
					(size 1.27 1.27)
				)
			)
		)
		(property "Author" "Antmicro"
			(at 218.44 79.375 0)
			(effects
				(font
					(size 1.27 1.27)
					(thickness 0.15)
				)
				(justify left bottom)
				(hide yes)
			)
		)
		(property "License" "Apache-2.0"
			(at 218.44 81.915 0)
			(effects
				(font
					(size 1.27 1.27)
					(thickness 0.15)
				)
				(justify left bottom)
				(hide yes)
			)
		)
		(pin "1"
		)
		(instances
			(project "sodimm-ddr5-tester"
				(path ""
					(reference "#PWR0180")
					(unit 1)
				)
			)
		)
	)
	(symbol
		(lib_id "antmicroSlideSwitches:CVS-03B")
		(at 330.2 232.41 0)
		(mirror y)
		(unit 1)
		(exclude_from_sim no)
		(in_bom yes)
		(on_board yes)
		(dnp no)
		(fields_autoplaced yes)
		(property "Reference" "SW1"
			(at 323.85 226.185 0)
			(effects
				(font
					(size 1.27 1.27)
					(thickness 0.15)
				)
			)
		)
		(property "Value" "CVS-03B"
			(at 323.85 228.7087 0)
			(effects
				(font
					(size 1.27 1.27)
					(thickness 0.15)
				)
			)
		)
		(property "Footprint" "antmicro-footprints:SW_DIP_SPSTx03_Slide_Copal_CVS-03xB_W5.9mm_P1mm"
			(at 303.53 240.03 0)
			(effects
				(font
					(size 1.27 1.27)
					(thickness 0.15)
				)
				(justify left bottom)
				(hide yes)
			)
		)
		(property "Datasheet" "https://www.mouser.com/datasheet/2/972/cvs-1827291.pdf"
			(at 303.53 242.57 0)
			(effects
				(font
					(size 1.27 1.27)
					(thickness 0.15)
				)
				(justify left bottom)
				(hide yes)
			)
		)
		(property "Description" ""
			(at 330.2 232.41 0)
			(effects
				(font
					(size 1.27 1.27)
				)
			)
		)
		(property "MPN" "CVS-03B"
			(at 303.53 245.11 0)
			(effects
				(font
					(size 1.27 1.27)
					(thickness 0.15)
				)
				(justify left bottom)
				(hide yes)
			)
		)
		(property "Manufacturer" "Nidec Components"
			(at 303.53 247.65 0)
			(effects
				(font
					(size 1.27 1.27)
					(thickness 0.15)
				)
				(justify left bottom)
				(hide yes)
			)
		)
		(property "Author" "Antmicro"
			(at 303.53 250.19 0)
			(effects
				(font
					(size 1.27 1.27)
					(thickness 0.15)
				)
				(justify left bottom)
				(hide yes)
			)
		)
		(property "License" "Apache-2.0"
			(at 303.53 252.73 0)
			(effects
				(font
					(size 1.27 1.27)
					(thickness 0.15)
				)
				(justify left bottom)
				(hide yes)
			)
		)
		(pin "1"
		)
		(pin "2"
		)
		(pin "3"
		)
		(pin "4"
		)
		(pin "5"
		)
		(pin "6"
		)
		(pin "7"
		)
		(instances
			(project "sodimm-ddr5-tester"
				(path ""
					(reference "SW1")
					(unit 1)
				)
			)
		)
	)
	(symbol
		(lib_id "antmicropower:+3V3")
		(at 250.19 226.06 0)
		(unit 1)
		(exclude_from_sim no)
		(in_bom yes)
		(on_board yes)
		(dnp no)
		(fields_autoplaced yes)
		(property "Reference" "#PWR0184"
			(at 250.19 229.87 0)
			(effects
				(font
					(size 1.27 1.27)
				)
				(hide yes)
			)
		)
		(property "Value" "+3V3"
			(at 247.015 223.52 0)
			(effects
				(font
					(size 1.27 1.27)
					(thickness 0.15)
				)
				(justify left bottom)
			)
		)
		(property "Footprint" ""
			(at 265.43 233.68 0)
			(effects
				(font
					(size 1.27 1.27)
					(thickness 0.15)
				)
				(justify left bottom)
				(hide yes)
			)
		)
		(property "Datasheet" ""
			(at 265.43 236.22 0)
			(effects
				(font
					(size 1.27 1.27)
					(thickness 0.15)
				)
				(justify left bottom)
				(hide yes)
			)
		)
		(property "Description" ""
			(at 250.19 226.06 0)
			(effects
				(font
					(size 1.27 1.27)
				)
			)
		)
		(property "Author" "Antmicro"
			(at 265.43 228.6 0)
			(effects
				(font
					(size 1.27 1.27)
					(thickness 0.15)
				)
				(justify left bottom)
				(hide yes)
			)
		)
		(property "License" "Apache-2.0"
			(at 265.43 231.14 0)
			(effects
				(font
					(size 1.27 1.27)
					(thickness 0.15)
				)
				(justify left bottom)
				(hide yes)
			)
		)
		(pin "1"
		)
		(instances
			(project "sodimm-ddr5-tester"
				(path ""
					(reference "#PWR0184")
					(unit 1)
				)
			)
		)
	)
	(symbol
		(lib_id "antmicropower:GND")
		(at 165.1 256.54 0)
		(unit 1)
		(exclude_from_sim no)
		(in_bom yes)
		(on_board yes)
		(dnp no)
		(property "Reference" "#PWR018"
			(at 165.1 262.89 0)
			(effects
				(font
					(size 1.27 1.27)
				)
				(hide yes)
			)
		)
		(property "Value" "GND"
			(at 163.068 260.858 0)
			(effects
				(font
					(size 1.27 1.27)
					(thickness 0.15)
				)
				(justify left)
			)
		)
		(property "Footprint" ""
			(at 173.99 264.16 0)
			(effects
				(font
					(size 1.27 1.27)
					(thickness 0.15)
				)
				(justify left bottom)
				(hide yes)
			)
		)
		(property "Datasheet" ""
			(at 173.99 269.24 0)
			(effects
				(font
					(size 1.27 1.27)
					(thickness 0.15)
				)
				(justify left bottom)
				(hide yes)
			)
		)
		(property "Description" ""
			(at 173.99 271.78 0)
			(effects
				(font
					(size 1.27 1.27)
				)
				(justify left bottom)
				(hide yes)
			)
		)
		(property "Author" "Antmicro"
			(at 173.99 264.16 0)
			(effects
				(font
					(size 1.27 1.27)
					(thickness 0.15)
				)
				(justify left bottom)
				(hide yes)
			)
		)
		(property "License" "Apache-2.0"
			(at 173.99 266.7 0)
			(effects
				(font
					(size 1.27 1.27)
					(thickness 0.15)
				)
				(justify left bottom)
				(hide yes)
			)
		)
		(pin "1"
		)
		(instances
			(project "sodimm-ddr5-tester"
				(path ""
					(reference "#PWR018")
					(unit 1)
				)
			)
		)
	)
	(symbol
		(lib_id "antmicroResistors0402:R_10k_0402")
		(at 339.09 228.6 270)
		(mirror x)
		(unit 1)
		(exclude_from_sim no)
		(in_bom yes)
		(on_board yes)
		(dnp no)
		(property "Reference" "R17"
			(at 337.82 225.425 90)
			(effects
				(font
					(size 1.27 1.27)
					(thickness 0.15)
				)
				(justify right)
			)
		)
		(property "Value" "R_10k_0402"
			(at 326.39 208.28 0)
			(effects
				(font
					(size 1.27 1.27)
					(thickness 0.15)
				)
				(justify left bottom)
				(hide yes)
			)
		)
		(property "Footprint" "antmicro-footprints:R_0402_1005Metric"
			(at 323.85 208.28 0)
			(effects
				(font
					(size 1.27 1.27)
					(thickness 0.15)
				)
				(justify left bottom)
				(hide yes)
			)
		)
		(property "Datasheet" "https://www.bourns.com/docs/product-datasheets/cr.pdf"
			(at 321.31 208.28 0)
			(effects
				(font
					(size 1.27 1.27)
					(thickness 0.15)
				)
				(justify left bottom)
				(hide yes)
			)
		)
		(property "Description" ""
			(at 339.09 228.6 0)
			(effects
				(font
					(size 1.27 1.27)
				)
			)
		)
		(property "MPN" "CR0402-FX-1002GLF"
			(at 318.77 208.28 0)
			(effects
				(font
					(size 1.27 1.27)
					(thickness 0.15)
				)
				(justify left bottom)
				(hide yes)
			)
		)
		(property "Manufacturer" "Bourns"
			(at 316.23 208.28 0)
			(effects
				(font
					(size 1.27 1.27)
					(thickness 0.15)
				)
				(justify left bottom)
				(hide yes)
			)
		)
		(property "License" "Apache-2.0"
			(at 313.69 208.28 0)
			(effects
				(font
					(size 1.27 1.27)
					(thickness 0.15)
				)
				(justify left bottom)
				(hide yes)
			)
		)
		(property "Author" "Antmicro"
			(at 311.15 208.28 0)
			(effects
				(font
					(size 1.27 1.27)
					(thickness 0.15)
				)
				(justify left bottom)
				(hide yes)
			)
		)
		(property "Val" "10k"
			(at 337.439 227.7531 90)
			(effects
				(font
					(size 1.27 1.27)
					(thickness 0.15)
				)
				(justify right)
			)
		)
		(property "Tolerance" "1%"
			(at 328.93 208.28 0)
			(effects
				(font
					(size 1.27 1.27)
				)
				(justify left bottom)
				(hide yes)
			)
		)
		(pin "1"
		)
		(pin "2"
		)
		(instances
			(project "sodimm-ddr5-tester"
				(path ""
					(reference "R17")
					(unit 1)
				)
			)
		)
	)
	(symbol
		(lib_id "antmicroTransistorsFETsMOSFETsSingle:BSS138PW,115")
		(at 242.57 251.46 0)
		(unit 1)
		(exclude_from_sim no)
		(in_bom yes)
		(on_board yes)
		(dnp no)
		(fields_autoplaced yes)
		(property "Reference" "Q2"
			(at 254 247.65 0)
			(effects
				(font
					(size 1.27 1.27)
					(thickness 0.15)
				)
				(justify left)
			)
		)
		(property "Value" "BSS138PW,115"
			(at 265.43 260.35 0)
			(effects
				(font
					(size 1.27 1.27)
					(thickness 0.15)
				)
				(justify left bottom)
				(hide yes)
			)
		)
		(property "Footprint" "antmicro-footprints:SC70-3"
			(at 265.43 262.89 0)
			(effects
				(font
					(size 1.27 1.27)
					(thickness 0.15)
				)
				(justify left bottom)
				(hide yes)
			)
		)
		(property "Datasheet" "https://assets.nexperia.com/documents/data-sheet/BSS138PW.pdf"
			(at 265.43 265.43 0)
			(effects
				(font
					(size 1.27 1.27)
					(thickness 0.15)
				)
				(justify left bottom)
				(hide yes)
			)
		)
		(property "Description" "Power MOSFET, N Channel, 60 V, 320 mA, 0.9 ohm, SOT-323, Surface Mount"
			(at 265.43 278.13 0)
			(effects
				(font
					(size 1.27 1.27)
				)
				(justify left bottom)
				(hide yes)
			)
		)
		(property "MPN" "BSS138PW,115"
			(at 254 250.19 0)
			(effects
				(font
					(size 1.27 1.27)
					(thickness 0.15)
				)
				(justify left)
			)
		)
		(property "Manufacturer" "Nexperia"
			(at 265.43 270.51 0)
			(effects
				(font
					(size 1.27 1.27)
					(thickness 0.15)
				)
				(justify left bottom)
				(hide yes)
			)
		)
		(property "Author" "Antmicro"
			(at 265.43 273.05 0)
			(effects
				(font
					(size 1.27 1.27)
					(thickness 0.15)
				)
				(justify left bottom)
				(hide yes)
			)
		)
		(property "License" "Apache-2.0"
			(at 265.43 275.59 0)
			(effects
				(font
					(size 1.27 1.27)
					(thickness 0.15)
				)
				(justify left bottom)
				(hide yes)
			)
		)
		(pin "3"
		)
		(pin "2"
		)
		(pin "1"
		)
		(instances
			(project "sodimm-ddr5-tester"
				(path ""
					(reference "Q2")
					(unit 1)
				)
			)
		)
	)
	(symbol
		(lib_id "antmicroGenericPinHeaders:PinHeader_2x7_P2mm_SMD_Shrouded_no-locator")
		(at 32.385 227.33 0)
		(unit 1)
		(exclude_from_sim no)
		(in_bom no)
		(on_board yes)
		(dnp yes)
		(property "Reference" "J1"
			(at 37.465 221.615 0)
			(effects
				(font
					(size 1.27 1.27)
				)
			)
		)
		(property "Value" "PinHeader_2x7_P2mm_SMD_Shrouded_no-locator"
			(at 57.785 232.41 0)
			(effects
				(font
					(size 1.27 1.27)
					(thickness 0.15)
				)
				(justify left bottom)
				(hide yes)
			)
		)
		(property "Footprint" "antmicro-footprints:PinHeader_2x7_P2mm_SMD_Shrouded_no-locator"
			(at 57.785 234.95 0)
			(effects
				(font
					(size 1.27 1.27)
					(thickness 0.15)
				)
				(justify left bottom)
				(hide yes)
			)
		)
		(property "Datasheet" "https://www.molex.com/pdm_docs/ps/PS-87831-027-001.pdf"
			(at 57.785 237.49 0)
			(effects
				(font
					(size 1.27 1.27)
					(thickness 0.15)
				)
				(justify left bottom)
				(hide yes)
			)
		)
		(property "Description" ""
			(at 32.385 227.33 0)
			(effects
				(font
					(size 1.27 1.27)
				)
			)
		)
		(property "MPN" "878321412"
			(at 37.465 224.155 0)
			(effects
				(font
					(size 1.27 1.27)
					(thickness 0.15)
				)
			)
		)
		(property "Manufacturer" "Molex"
			(at 57.785 242.57 0)
			(effects
				(font
					(size 1.27 1.27)
					(thickness 0.15)
				)
				(justify left bottom)
				(hide yes)
			)
		)
		(property "Author" "Antmicro"
			(at 57.785 245.11 0)
			(effects
				(font
					(size 1.27 1.27)
					(thickness 0.15)
				)
				(justify left bottom)
				(hide yes)
			)
		)
		(property "License" "Apache-2.0"
			(at 57.785 247.65 0)
			(effects
				(font
					(size 1.27 1.27)
					(thickness 0.15)
				)
				(justify left bottom)
				(hide yes)
			)
		)
		(pin "1"
		)
		(pin "10"
		)
		(pin "11"
		)
		(pin "12"
		)
		(pin "13"
		)
		(pin "14"
		)
		(pin "2"
		)
		(pin "3"
		)
		(pin "4"
		)
		(pin "5"
		)
		(pin "6"
		)
		(pin "7"
		)
		(pin "8"
		)
		(pin "9"
		)
		(instances
			(project "sodimm-ddr5-tester"
				(path ""
					(reference "J1")
					(unit 1)
				)
			)
		)
	)
	(symbol
		(lib_id "antmicropower:+3V3")
		(at 47.625 222.885 0)
		(unit 1)
		(exclude_from_sim no)
		(in_bom yes)
		(on_board yes)
		(dnp no)
		(property "Reference" "#PWR0185"
			(at 47.625 226.695 0)
			(effects
				(font
					(size 1.27 1.27)
				)
				(hide yes)
			)
		)
		(property "Value" "+3V3"
			(at 44.45 220.345 0)
			(effects
				(font
					(size 1.27 1.27)
					(thickness 0.15)
				)
				(justify left bottom)
			)
		)
		(property "Footprint" ""
			(at 62.865 230.505 0)
			(effects
				(font
					(size 1.27 1.27)
					(thickness 0.15)
				)
				(justify left bottom)
				(hide yes)
			)
		)
		(property "Datasheet" ""
			(at 62.865 233.045 0)
			(effects
				(font
					(size 1.27 1.27)
					(thickness 0.15)
				)
				(justify left bottom)
				(hide yes)
			)
		)
		(property "Description" ""
			(at 47.625 222.885 0)
			(effects
				(font
					(size 1.27 1.27)
				)
			)
		)
		(property "Author" "Antmicro"
			(at 62.865 225.425 0)
			(effects
				(font
					(size 1.27 1.27)
					(thickness 0.15)
				)
				(justify left bottom)
				(hide yes)
			)
		)
		(property "License" "Apache-2.0"
			(at 62.865 227.965 0)
			(effects
				(font
					(size 1.27 1.27)
					(thickness 0.15)
				)
				(justify left bottom)
				(hide yes)
			)
		)
		(pin "1"
		)
		(instances
			(project "sodimm-ddr5-tester"
				(path ""
					(reference "#PWR0185")
					(unit 1)
				)
			)
		)
	)
	(symbol
		(lib_id "antmicropower:+3V3")
		(at 165.1 226.06 0)
		(unit 1)
		(exclude_from_sim no)
		(in_bom yes)
		(on_board yes)
		(dnp no)
		(fields_autoplaced yes)
		(property "Reference" "#PWR0176"
			(at 165.1 229.87 0)
			(effects
				(font
					(size 1.27 1.27)
				)
				(hide yes)
			)
		)
		(property "Value" "+3V3"
			(at 161.925 223.52 0)
			(effects
				(font
					(size 1.27 1.27)
					(thickness 0.15)
				)
				(justify left bottom)
			)
		)
		(property "Footprint" ""
			(at 180.34 233.68 0)
			(effects
				(font
					(size 1.27 1.27)
					(thickness 0.15)
				)
				(justify left bottom)
				(hide yes)
			)
		)
		(property "Datasheet" ""
			(at 180.34 236.22 0)
			(effects
				(font
					(size 1.27 1.27)
					(thickness 0.15)
				)
				(justify left bottom)
				(hide yes)
			)
		)
		(property "Description" ""
			(at 165.1 226.06 0)
			(effects
				(font
					(size 1.27 1.27)
				)
			)
		)
		(property "Author" "Antmicro"
			(at 180.34 228.6 0)
			(effects
				(font
					(size 1.27 1.27)
					(thickness 0.15)
				)
				(justify left bottom)
				(hide yes)
			)
		)
		(property "License" "Apache-2.0"
			(at 180.34 231.14 0)
			(effects
				(font
					(size 1.27 1.27)
					(thickness 0.15)
				)
				(justify left bottom)
				(hide yes)
			)
		)
		(pin "1"
		)
		(instances
			(project "sodimm-ddr5-tester"
				(path ""
					(reference "#PWR0176")
					(unit 1)
				)
			)
		)
	)
	(symbol
		(lib_id "antmicroLEDIndicationDiscrete:LED_G_0603_KP-1608CGCK")
		(at 165.1 227.33 270)
		(unit 1)
		(exclude_from_sim no)
		(in_bom yes)
		(on_board yes)
		(dnp no)
		(property "Reference" "D1"
			(at 168.148 230.3094 90)
			(effects
				(font
					(size 1.27 1.27)
				)
				(justify left)
			)
		)
		(property "Value" "LED_G_0603_KP-1608CGCK"
			(at 181.483 232.664 90)
			(effects
				(font
					(size 1.27 1.27)
					(thickness 0.15)
				)
			)
		)
		(property "Footprint" "antmicro-footprints:LED_0603_1608Metric_G"
			(at 154.94 250.19 0)
			(effects
				(font
					(size 1.27 1.27)
					(thickness 0.15)
				)
				(justify left bottom)
				(hide yes)
			)
		)
		(property "Datasheet" "http://www.farnell.com/datasheets/2045956.pdf"
			(at 152.4 250.19 0)
			(effects
				(font
					(size 1.27 1.27)
					(thickness 0.15)
				)
				(justify left bottom)
				(hide yes)
			)
		)
		(property "Description" ""
			(at 165.1 227.33 0)
			(effects
				(font
					(size 1.27 1.27)
				)
			)
		)
		(property "MPN" "KP-1608CGCK"
			(at 168.148 232.8397 90)
			(effects
				(font
					(size 1.27 1.27)
					(thickness 0.15)
				)
				(justify left)
				(hide yes)
			)
		)
		(property "Manufacturer" "Kingbright"
			(at 147.32 250.19 0)
			(effects
				(font
					(size 1.27 1.27)
					(thickness 0.15)
				)
				(justify left bottom)
				(hide yes)
			)
		)
		(property "Author" "Antmicro"
			(at 144.78 250.19 0)
			(effects
				(font
					(size 1.27 1.27)
					(thickness 0.15)
				)
				(justify left bottom)
				(hide yes)
			)
		)
		(property "License" "Apache-2.0"
			(at 142.24 250.19 0)
			(effects
				(font
					(size 1.27 1.27)
					(thickness 0.15)
				)
				(justify left bottom)
				(hide yes)
			)
		)
		(pin "1"
		)
		(pin "2"
		)
		(instances
			(project "sodimm-ddr5-tester"
				(path ""
					(reference "D1")
					(unit 1)
				)
			)
		)
	)
	(symbol
		(lib_id "antmicroResistors0402:R_10k_0402")
		(at 347.345 228.6 270)
		(mirror x)
		(unit 1)
		(exclude_from_sim no)
		(in_bom yes)
		(on_board yes)
		(dnp no)
		(property "Reference" "R15"
			(at 346.075 225.425 90)
			(effects
				(font
					(size 1.27 1.27)
					(thickness 0.15)
				)
				(justify right)
			)
		)
		(property "Value" "R_10k_0402"
			(at 334.645 208.28 0)
			(effects
				(font
					(size 1.27 1.27)
					(thickness 0.15)
				)
				(justify left bottom)
				(hide yes)
			)
		)
		(property "Footprint" "antmicro-footprints:R_0402_1005Metric"
			(at 332.105 208.28 0)
			(effects
				(font
					(size 1.27 1.27)
					(thickness 0.15)
				)
				(justify left bottom)
				(hide yes)
			)
		)
		(property "Datasheet" "https://www.bourns.com/docs/product-datasheets/cr.pdf"
			(at 329.565 208.28 0)
			(effects
				(font
					(size 1.27 1.27)
					(thickness 0.15)
				)
				(justify left bottom)
				(hide yes)
			)
		)
		(property "Description" ""
			(at 347.345 228.6 0)
			(effects
				(font
					(size 1.27 1.27)
				)
			)
		)
		(property "MPN" "CR0402-FX-1002GLF"
			(at 327.025 208.28 0)
			(effects
				(font
					(size 1.27 1.27)
					(thickness 0.15)
				)
				(justify left bottom)
				(hide yes)
			)
		)
		(property "Manufacturer" "Bourns"
			(at 324.485 208.28 0)
			(effects
				(font
					(size 1.27 1.27)
					(thickness 0.15)
				)
				(justify left bottom)
				(hide yes)
			)
		)
		(property "License" "Apache-2.0"
			(at 321.945 208.28 0)
			(effects
				(font
					(size 1.27 1.27)
					(thickness 0.15)
				)
				(justify left bottom)
				(hide yes)
			)
		)
		(property "Author" "Antmicro"
			(at 319.405 208.28 0)
			(effects
				(font
					(size 1.27 1.27)
					(thickness 0.15)
				)
				(justify left bottom)
				(hide yes)
			)
		)
		(property "Val" "10k"
			(at 345.694 227.7531 90)
			(effects
				(font
					(size 1.27 1.27)
					(thickness 0.15)
				)
				(justify right)
			)
		)
		(property "Tolerance" "1%"
			(at 337.185 208.28 0)
			(effects
				(font
					(size 1.27 1.27)
				)
				(justify left bottom)
				(hide yes)
			)
		)
		(pin "1"
		)
		(pin "2"
		)
		(instances
			(project "sodimm-ddr5-tester"
				(path ""
					(reference "R15")
					(unit 1)
				)
			)
		)
	)
	(symbol
		(lib_id "antmicroTVSDiodes:TPD4E05U06QDQARQ1")
		(at 88.9 229.87 0)
		(mirror y)
		(unit 1)
		(exclude_from_sim no)
		(in_bom no)
		(on_board yes)
		(dnp yes)
		(property "Reference" "U2"
			(at 79.248 233.4844 0)
			(effects
				(font
					(size 1.27 1.27)
					(thickness 0.15)
				)
				(justify left)
			)
		)
		(property "Value" "TPD4E05U06QDQARQ1"
			(at 79.248 236.0081 0)
			(effects
				(font
					(size 1.27 1.27)
					(thickness 0.15)
				)
				(justify left)
			)
		)
		(property "Footprint" "antmicro-footprints:USON-10_2.5x1mm_P0.5mm"
			(at 64.77 234.95 0)
			(effects
				(font
					(size 1.27 1.27)
					(thickness 0.15)
				)
				(justify left bottom)
				(hide yes)
			)
		)
		(property "Datasheet" "https://www.ti.com/lit/ds/symlink/tpd4e05u06-q1.pdf?HQS=dis-mous-null-mousermode-dsf-pf-null-wwe&ts=1663591265741&ref_url=https%253A%252F%252Fwww.mouser.com%252F"
			(at 64.77 237.49 0)
			(effects
				(font
					(size 1.27 1.27)
					(thickness 0.15)
				)
				(justify left bottom)
				(hide yes)
			)
		)
		(property "Description" ""
			(at 88.9 229.87 0)
			(effects
				(font
					(size 1.27 1.27)
				)
			)
		)
		(property "Manufacturer" "Texas Instruments"
			(at 64.77 240.03 0)
			(effects
				(font
					(size 1.27 1.27)
					(thickness 0.15)
				)
				(justify left bottom)
				(hide yes)
			)
		)
		(property "MPN" "TPD4E05U06QDQARQ1"
			(at 64.77 242.57 0)
			(effects
				(font
					(size 1.27 1.27)
					(thickness 0.15)
				)
				(justify left bottom)
				(hide yes)
			)
		)
		(property "Author" "Antmicro"
			(at 64.77 245.11 0)
			(effects
				(font
					(size 1.27 1.27)
					(thickness 0.15)
				)
				(justify left bottom)
				(hide yes)
			)
		)
		(property "License" "Apache-2.0"
			(at 64.77 247.65 0)
			(effects
				(font
					(size 1.27 1.27)
					(thickness 0.15)
				)
				(justify left bottom)
				(hide yes)
			)
		)
		(pin "1"
		)
		(pin "10"
		)
		(pin "2"
		)
		(pin "3"
		)
		(pin "4"
		)
		(pin "5"
		)
		(pin "6"
		)
		(pin "7"
		)
		(pin "8"
		)
		(pin "9"
		)
		(instances
			(project "sodimm-ddr5-tester"
				(path ""
					(reference "U2")
					(unit 1)
				)
			)
		)
	)
	(symbol
		(lib_id "antmicroTransistorsFETsMOSFETsSingle:BSS138PW,115")
		(at 157.48 251.46 0)
		(unit 1)
		(exclude_from_sim no)
		(in_bom yes)
		(on_board yes)
		(dnp no)
		(fields_autoplaced yes)
		(property "Reference" "Q1"
			(at 168.91 247.65 0)
			(effects
				(font
					(size 1.27 1.27)
					(thickness 0.15)
				)
				(justify left)
			)
		)
		(property "Value" "BSS138PW,115"
			(at 180.34 260.35 0)
			(effects
				(font
					(size 1.27 1.27)
					(thickness 0.15)
				)
				(justify left bottom)
				(hide yes)
			)
		)
		(property "Footprint" "antmicro-footprints:SC70-3"
			(at 180.34 262.89 0)
			(effects
				(font
					(size 1.27 1.27)
					(thickness 0.15)
				)
				(justify left bottom)
				(hide yes)
			)
		)
		(property "Datasheet" "https://assets.nexperia.com/documents/data-sheet/BSS138PW.pdf"
			(at 180.34 265.43 0)
			(effects
				(font
					(size 1.27 1.27)
					(thickness 0.15)
				)
				(justify left bottom)
				(hide yes)
			)
		)
		(property "Description" "Power MOSFET, N Channel, 60 V, 320 mA, 0.9 ohm, SOT-323, Surface Mount"
			(at 180.34 278.13 0)
			(effects
				(font
					(size 1.27 1.27)
				)
				(justify left bottom)
				(hide yes)
			)
		)
		(property "MPN" "BSS138PW,115"
			(at 168.91 250.19 0)
			(effects
				(font
					(size 1.27 1.27)
					(thickness 0.15)
				)
				(justify left)
			)
		)
		(property "Manufacturer" "Nexperia"
			(at 180.34 270.51 0)
			(effects
				(font
					(size 1.27 1.27)
					(thickness 0.15)
				)
				(justify left bottom)
				(hide yes)
			)
		)
		(property "Author" "Antmicro"
			(at 180.34 273.05 0)
			(effects
				(font
					(size 1.27 1.27)
					(thickness 0.15)
				)
				(justify left bottom)
				(hide yes)
			)
		)
		(property "License" "Apache-2.0"
			(at 180.34 275.59 0)
			(effects
				(font
					(size 1.27 1.27)
					(thickness 0.15)
				)
				(justify left bottom)
				(hide yes)
			)
		)
		(pin "3"
		)
		(pin "2"
		)
		(pin "1"
		)
		(instances
			(project ""
				(path ""
					(reference "Q1")
					(unit 1)
				)
			)
		)
	)
	(symbol
		(lib_id "antmicroPushbuttonSwitches:SW_KMR211NGLFS_SMD")
		(at 173.99 120.65 270)
		(unit 1)
		(exclude_from_sim no)
		(in_bom yes)
		(on_board yes)
		(dnp no)
		(fields_autoplaced yes)
		(property "Reference" "SW2"
			(at 177.546 124.8994 90)
			(effects
				(font
					(size 1.27 1.27)
					(thickness 0.15)
				)
				(justify left)
			)
		)
		(property "Value" "SW_KMR211NGLFS_SMD"
			(at 166.37 146.05 0)
			(effects
				(font
					(size 1.27 1.27)
					(thickness 0.15)
				)
				(justify left bottom)
				(hide yes)
			)
		)
		(property "Footprint" "antmicro-footprints:SW_KMR211NGLFS_SMD"
			(at 163.83 146.05 0)
			(effects
				(font
					(size 1.27 1.27)
					(thickness 0.15)
				)
				(justify left bottom)
				(hide yes)
			)
		)
		(property "Datasheet" "http://www.farnell.com/datasheets/2631211.pdf"
			(at 161.29 146.05 0)
			(effects
				(font
					(size 1.27 1.27)
					(thickness 0.15)
				)
				(justify left bottom)
				(hide yes)
			)
		)
		(property "Description" ""
			(at 173.99 120.65 0)
			(effects
				(font
					(size 1.27 1.27)
				)
			)
		)
		(property "MPN" "KMR211NGLFS"
			(at 177.546 127.4231 90)
			(effects
				(font
					(size 1.27 1.27)
					(thickness 0.15)
				)
				(justify left)
			)
		)
		(property "Manufacturer" "C&K"
			(at 158.75 146.05 0)
			(effects
				(font
					(size 1.27 1.27)
					(thickness 0.15)
				)
				(justify left bottom)
				(hide yes)
			)
		)
		(property "Author" "Antmicro"
			(at 156.21 146.05 0)
			(effects
				(font
					(size 1.27 1.27)
					(thickness 0.15)
				)
				(justify left bottom)
				(hide yes)
			)
		)
		(property "License" "Apache-2.0"
			(at 153.67 146.05 0)
			(effects
				(font
					(size 1.27 1.27)
					(thickness 0.15)
				)
				(justify left bottom)
				(hide yes)
			)
		)
		(pin "1"
		)
		(pin "2"
		)
		(pin "3"
		)
		(pin "4"
		)
		(instances
			(project "sodimm-ddr5-tester"
				(path ""
					(reference "SW2")
					(unit 1)
				)
			)
		)
	)
	(symbol
		(lib_id "antmicroResistors0402:R_10k_0402")
		(at 354.965 228.6 270)
		(mirror x)
		(unit 1)
		(exclude_from_sim no)
		(in_bom yes)
		(on_board yes)
		(dnp no)
		(property "Reference" "R14"
			(at 353.695 225.425 90)
			(effects
				(font
					(size 1.27 1.27)
					(thickness 0.15)
				)
				(justify right)
			)
		)
		(property "Value" "R_10k_0402"
			(at 342.265 208.28 0)
			(effects
				(font
					(size 1.27 1.27)
					(thickness 0.15)
				)
				(justify left bottom)
				(hide yes)
			)
		)
		(property "Footprint" "antmicro-footprints:R_0402_1005Metric"
			(at 339.725 208.28 0)
			(effects
				(font
					(size 1.27 1.27)
					(thickness 0.15)
				)
				(justify left bottom)
				(hide yes)
			)
		)
		(property "Datasheet" "https://www.bourns.com/docs/product-datasheets/cr.pdf"
			(at 337.185 208.28 0)
			(effects
				(font
					(size 1.27 1.27)
					(thickness 0.15)
				)
				(justify left bottom)
				(hide yes)
			)
		)
		(property "Description" ""
			(at 354.965 228.6 0)
			(effects
				(font
					(size 1.27 1.27)
				)
			)
		)
		(property "MPN" "CR0402-FX-1002GLF"
			(at 334.645 208.28 0)
			(effects
				(font
					(size 1.27 1.27)
					(thickness 0.15)
				)
				(justify left bottom)
				(hide yes)
			)
		)
		(property "Manufacturer" "Bourns"
			(at 332.105 208.28 0)
			(effects
				(font
					(size 1.27 1.27)
					(thickness 0.15)
				)
				(justify left bottom)
				(hide yes)
			)
		)
		(property "License" "Apache-2.0"
			(at 329.565 208.28 0)
			(effects
				(font
					(size 1.27 1.27)
					(thickness 0.15)
				)
				(justify left bottom)
				(hide yes)
			)
		)
		(property "Author" "Antmicro"
			(at 327.025 208.28 0)
			(effects
				(font
					(size 1.27 1.27)
					(thickness 0.15)
				)
				(justify left bottom)
				(hide yes)
			)
		)
		(property "Val" "10k"
			(at 353.314 227.7531 90)
			(effects
				(font
					(size 1.27 1.27)
					(thickness 0.15)
				)
				(justify right)
			)
		)
		(property "Tolerance" "1%"
			(at 344.805 208.28 0)
			(effects
				(font
					(size 1.27 1.27)
				)
				(justify left bottom)
				(hide yes)
			)
		)
		(pin "1"
		)
		(pin "2"
		)
		(instances
			(project "sodimm-ddr5-tester"
				(path ""
					(reference "R14")
					(unit 1)
				)
			)
		)
	)
	(symbol
		(lib_id "antmicropower:+3V3")
		(at 163.195 94.615 0)
		(unit 1)
		(exclude_from_sim no)
		(in_bom yes)
		(on_board yes)
		(dnp no)
		(property "Reference" "#PWR0188"
			(at 163.195 98.425 0)
			(effects
				(font
					(size 1.27 1.27)
				)
				(hide yes)
			)
		)
		(property "Value" "+3V3"
			(at 160.02 92.075 0)
			(effects
				(font
					(size 1.27 1.27)
					(thickness 0.15)
				)
				(justify left bottom)
			)
		)
		(property "Footprint" ""
			(at 178.435 102.235 0)
			(effects
				(font
					(size 1.27 1.27)
					(thickness 0.15)
				)
				(justify left bottom)
				(hide yes)
			)
		)
		(property "Datasheet" ""
			(at 178.435 104.775 0)
			(effects
				(font
					(size 1.27 1.27)
					(thickness 0.15)
				)
				(justify left bottom)
				(hide yes)
			)
		)
		(property "Description" ""
			(at 163.195 94.615 0)
			(effects
				(font
					(size 1.27 1.27)
				)
			)
		)
		(property "Author" "Antmicro"
			(at 178.435 97.155 0)
			(effects
				(font
					(size 1.27 1.27)
					(thickness 0.15)
				)
				(justify left bottom)
				(hide yes)
			)
		)
		(property "License" "Apache-2.0"
			(at 178.435 99.695 0)
			(effects
				(font
					(size 1.27 1.27)
					(thickness 0.15)
				)
				(justify left bottom)
				(hide yes)
			)
		)
		(pin "1"
		)
		(instances
			(project "sodimm-ddr5-tester"
				(path ""
					(reference "#PWR0188")
					(unit 1)
				)
			)
		)
	)
	(symbol
		(lib_id "antmicropower:+3V3")
		(at 347.345 219.71 0)
		(unit 1)
		(exclude_from_sim no)
		(in_bom yes)
		(on_board yes)
		(dnp no)
		(fields_autoplaced yes)
		(property "Reference" "#PWR0189"
			(at 347.345 223.52 0)
			(effects
				(font
					(size 1.27 1.27)
				)
				(hide yes)
			)
		)
		(property "Value" "+3V3"
			(at 344.17 217.17 0)
			(effects
				(font
					(size 1.27 1.27)
					(thickness 0.15)
				)
				(justify left bottom)
			)
		)
		(property "Footprint" ""
			(at 362.585 227.33 0)
			(effects
				(font
					(size 1.27 1.27)
					(thickness 0.15)
				)
				(justify left bottom)
				(hide yes)
			)
		)
		(property "Datasheet" ""
			(at 362.585 229.87 0)
			(effects
				(font
					(size 1.27 1.27)
					(thickness 0.15)
				)
				(justify left bottom)
				(hide yes)
			)
		)
		(property "Description" ""
			(at 347.345 219.71 0)
			(effects
				(font
					(size 1.27 1.27)
				)
			)
		)
		(property "Author" "Antmicro"
			(at 362.585 222.25 0)
			(effects
				(font
					(size 1.27 1.27)
					(thickness 0.15)
				)
				(justify left bottom)
				(hide yes)
			)
		)
		(property "License" "Apache-2.0"
			(at 362.585 224.79 0)
			(effects
				(font
					(size 1.27 1.27)
					(thickness 0.15)
				)
				(justify left bottom)
				(hide yes)
			)
		)
		(pin "1"
		)
		(instances
			(project "sodimm-ddr5-tester"
				(path ""
					(reference "#PWR0189")
					(unit 1)
				)
			)
		)
	)
	(symbol
		(lib_id "antmicroTransistorsFETsMOSFETsSingle:BSS138PW,115")
		(at 199.39 251.46 0)
		(unit 1)
		(exclude_from_sim no)
		(in_bom yes)
		(on_board yes)
		(dnp no)
		(fields_autoplaced yes)
		(property "Reference" "Q3"
			(at 210.82 247.65 0)
			(effects
				(font
					(size 1.27 1.27)
					(thickness 0.15)
				)
				(justify left)
			)
		)
		(property "Value" "BSS138PW,115"
			(at 222.25 260.35 0)
			(effects
				(font
					(size 1.27 1.27)
					(thickness 0.15)
				)
				(justify left bottom)
				(hide yes)
			)
		)
		(property "Footprint" "antmicro-footprints:SC70-3"
			(at 222.25 262.89 0)
			(effects
				(font
					(size 1.27 1.27)
					(thickness 0.15)
				)
				(justify left bottom)
				(hide yes)
			)
		)
		(property "Datasheet" "https://assets.nexperia.com/documents/data-sheet/BSS138PW.pdf"
			(at 222.25 265.43 0)
			(effects
				(font
					(size 1.27 1.27)
					(thickness 0.15)
				)
				(justify left bottom)
				(hide yes)
			)
		)
		(property "Description" "Power MOSFET, N Channel, 60 V, 320 mA, 0.9 ohm, SOT-323, Surface Mount"
			(at 222.25 278.13 0)
			(effects
				(font
					(size 1.27 1.27)
				)
				(justify left bottom)
				(hide yes)
			)
		)
		(property "MPN" "BSS138PW,115"
			(at 210.82 250.19 0)
			(effects
				(font
					(size 1.27 1.27)
					(thickness 0.15)
				)
				(justify left)
			)
		)
		(property "Manufacturer" "Nexperia"
			(at 222.25 270.51 0)
			(effects
				(font
					(size 1.27 1.27)
					(thickness 0.15)
				)
				(justify left bottom)
				(hide yes)
			)
		)
		(property "Author" "Antmicro"
			(at 222.25 273.05 0)
			(effects
				(font
					(size 1.27 1.27)
					(thickness 0.15)
				)
				(justify left bottom)
				(hide yes)
			)
		)
		(property "License" "Apache-2.0"
			(at 222.25 275.59 0)
			(effects
				(font
					(size 1.27 1.27)
					(thickness 0.15)
				)
				(justify left bottom)
				(hide yes)
			)
		)
		(pin "3"
		)
		(pin "2"
		)
		(pin "1"
		)
		(instances
			(project "sodimm-ddr5-tester"
				(path ""
					(reference "Q3")
					(unit 1)
				)
			)
		)
	)
	(symbol
		(lib_id "antmicropower:+3V3")
		(at 248.285 76.2 0)
		(unit 1)
		(exclude_from_sim no)
		(in_bom yes)
		(on_board yes)
		(dnp no)
		(property "Reference" "#PWR0181"
			(at 248.285 80.01 0)
			(effects
				(font
					(size 1.27 1.27)
				)
				(hide yes)
			)
		)
		(property "Value" "+3V3"
			(at 245.11 73.66 0)
			(effects
				(font
					(size 1.27 1.27)
					(thickness 0.15)
				)
				(justify left bottom)
			)
		)
		(property "Footprint" ""
			(at 263.525 83.82 0)
			(effects
				(font
					(size 1.27 1.27)
					(thickness 0.15)
				)
				(justify left bottom)
				(hide yes)
			)
		)
		(property "Datasheet" ""
			(at 263.525 86.36 0)
			(effects
				(font
					(size 1.27 1.27)
					(thickness 0.15)
				)
				(justify left bottom)
				(hide yes)
			)
		)
		(property "Description" ""
			(at 248.285 76.2 0)
			(effects
				(font
					(size 1.27 1.27)
				)
			)
		)
		(property "Author" "Antmicro"
			(at 263.525 78.74 0)
			(effects
				(font
					(size 1.27 1.27)
					(thickness 0.15)
				)
				(justify left bottom)
				(hide yes)
			)
		)
		(property "License" "Apache-2.0"
			(at 263.525 81.28 0)
			(effects
				(font
					(size 1.27 1.27)
					(thickness 0.15)
				)
				(justify left bottom)
				(hide yes)
			)
		)
		(pin "1"
		)
		(instances
			(project "sodimm-ddr5-tester"
				(path ""
					(reference "#PWR0181")
					(unit 1)
				)
			)
		)
	)
	(symbol
		(lib_id "antmicropower:+3V3")
		(at 207.01 226.06 0)
		(unit 1)
		(exclude_from_sim no)
		(in_bom yes)
		(on_board yes)
		(dnp no)
		(fields_autoplaced yes)
		(property "Reference" "#PWR0178"
			(at 207.01 229.87 0)
			(effects
				(font
					(size 1.27 1.27)
				)
				(hide yes)
			)
		)
		(property "Value" "+3V3"
			(at 203.835 223.52 0)
			(effects
				(font
					(size 1.27 1.27)
					(thickness 0.15)
				)
				(justify left bottom)
			)
		)
		(property "Footprint" ""
			(at 222.25 233.68 0)
			(effects
				(font
					(size 1.27 1.27)
					(thickness 0.15)
				)
				(justify left bottom)
				(hide yes)
			)
		)
		(property "Datasheet" ""
			(at 222.25 236.22 0)
			(effects
				(font
					(size 1.27 1.27)
					(thickness 0.15)
				)
				(justify left bottom)
				(hide yes)
			)
		)
		(property "Description" ""
			(at 207.01 226.06 0)
			(effects
				(font
					(size 1.27 1.27)
				)
			)
		)
		(property "Author" "Antmicro"
			(at 222.25 228.6 0)
			(effects
				(font
					(size 1.27 1.27)
					(thickness 0.15)
				)
				(justify left bottom)
				(hide yes)
			)
		)
		(property "License" "Apache-2.0"
			(at 222.25 231.14 0)
			(effects
				(font
					(size 1.27 1.27)
					(thickness 0.15)
				)
				(justify left bottom)
				(hide yes)
			)
		)
		(pin "1"
		)
		(instances
			(project "sodimm-ddr5-tester"
				(path ""
					(reference "#PWR0178")
					(unit 1)
				)
			)
		)
	)
	(symbol
		(lib_id "antmicropower:GND")
		(at 313.69 243.205 0)
		(mirror y)
		(unit 1)
		(exclude_from_sim no)
		(in_bom yes)
		(on_board yes)
		(dnp no)
		(property "Reference" "#PWR0177"
			(at 313.69 249.555 0)
			(effects
				(font
					(size 1.27 1.27)
				)
				(hide yes)
			)
		)
		(property "Value" "GND"
			(at 315.595 247.65 0)
			(effects
				(font
					(size 1.27 1.27)
					(thickness 0.15)
				)
				(justify left bottom)
			)
		)
		(property "Footprint" ""
			(at 304.8 250.825 0)
			(effects
				(font
					(size 1.27 1.27)
					(thickness 0.15)
				)
				(justify left bottom)
				(hide yes)
			)
		)
		(property "Datasheet" ""
			(at 304.8 255.905 0)
			(effects
				(font
					(size 1.27 1.27)
					(thickness 0.15)
				)
				(justify left bottom)
				(hide yes)
			)
		)
		(property "Description" ""
			(at 304.8 258.445 0)
			(effects
				(font
					(size 1.27 1.27)
				)
				(justify left bottom)
				(hide yes)
			)
		)
		(property "Author" "Antmicro"
			(at 304.8 250.825 0)
			(effects
				(font
					(size 1.27 1.27)
					(thickness 0.15)
				)
				(justify left bottom)
				(hide yes)
			)
		)
		(property "License" "Apache-2.0"
			(at 304.8 253.365 0)
			(effects
				(font
					(size 1.27 1.27)
					(thickness 0.15)
				)
				(justify left bottom)
				(hide yes)
			)
		)
		(pin "1"
		)
		(instances
			(project "sodimm-ddr5-tester"
				(path ""
					(reference "#PWR0177")
					(unit 1)
				)
			)
		)
	)
)
